G04 ================== begin FILE IDENTIFICATION RECORD ==================*
G04 Layout Name:  D:/<user>/Wistron_project/16316-1/gbr-0621/16316-1.brd*
G04 Film Name:    SE_REF_L1*
G04 File Format:  Gerber RS274X*
G04 File Origin:  Cadence Allegro 16.5-S056*
G04 Origin Date:  Wed Jun 21 09:32:25 2017*
G04 *
G04 Layer:  BOARD GEOMETRY/SE_REF_L1_TBL*
G04 Layer:  BOARD GEOMETRY/SE_REF_L1_TOP*
G04 Layer:  BOARD GEOMETRY/PANEL_OUTLINE*
G04 *
G04 Offset:    (0.00 0.00)*
G04 Mirror:    No*
G04 Mode:      Positive*
G04 Rotation:  0*
G04 FullContactRelief:  No*
G04 UndefLineWidth:     6.00*
G04 ================== end FILE IDENTIFICATION RECORD ====================*
%FSLAX35Y35*MOIN*%
%IR0*IPPOS*OFA0.00000B0.00000*MIA0B0*SFA1.00000B1.00000*%
%ADD10C,.02*%
%ADD11C,.005*%
%ADD12C,.006*%
G75*
%LPD*%
G75*
G54D10*
G01X877071Y467216D02*
X1594571D01*
G01X877071Y536516D02*
Y467216D01*
G01Y536516D02*
X1594571D01*
G01X877071Y501866D02*
X1594571D01*
G01X1052071Y536516D02*
Y467216D01*
G01X1279571Y536516D02*
Y467216D01*
G01X1384571Y536516D02*
Y467216D01*
G01X1594571Y536516D02*
Y467216D01*
G54D11*
G01X39612Y174281D02*
X34425Y179468D01*
G01X47362Y170656D02*
X43487Y166781D01*
G01X47362Y174281D02*
Y170656D01*
G01X44739Y174281D02*
X38814Y180206D01*
G01X47362Y174281D02*
X44739D01*
G01X56500Y234577D02*
X56541Y234536D01*
G01X56500Y239800D02*
Y234577D01*
G01X32405Y180754D02*
X33691Y179468D01*
G01X32405Y184267D02*
Y180754D01*
G01X34425Y179468D02*
X33691D01*
G01X45938Y237238D02*
X49320Y240620D01*
G01X45938Y235454D02*
Y237238D01*
G01X41938Y237338D02*
X45650Y241050D01*
G01X41938Y235454D02*
Y237338D01*
G01X45938Y229948D02*
Y231954D01*
G01X47025Y228861D02*
X45938Y229948D01*
G01X50082Y228861D02*
X47025D01*
G01X51200Y227743D02*
X50082Y228861D01*
G01X51200Y226100D02*
Y227743D01*
G01X49979Y222079D02*
Y219450D01*
G01X51200Y223300D02*
X49979Y222079D01*
G01X51200Y226100D02*
Y223300D01*
G01X36405Y182615D02*
X38814Y180206D01*
G01X36405Y184267D02*
Y182615D01*
G01X48010Y224390D02*
X46200Y226200D01*
G01X48010Y219750D02*
Y224390D01*
G01X45854Y226546D02*
X46200Y226200D01*
G01X43737Y226546D02*
X45854D01*
G01X41938Y228345D02*
X43737Y226546D01*
G01X41938Y231954D02*
Y228345D01*
G01X34100Y219050D02*
X29650Y223500D01*
G01X34100Y217500D02*
Y219050D01*
G01X29650Y223500D02*
Y227500D01*
G01D02*
Y235500D01*
G01Y237992D02*
Y235500D01*
G01X39325Y217500D02*
X34100D01*
G01X42204Y214621D02*
X39325Y217500D01*
G01X45150Y214621D02*
X42204D01*
G01X41450Y268450D02*
Y266100D01*
G01X42600Y269600D02*
X41450Y268450D01*
G01X48900Y269600D02*
X42600D01*
G01X52400Y266100D02*
X48900Y269600D01*
G01X52400Y247119D02*
Y266100D01*
G01X56500Y243019D02*
X52400Y247119D01*
G01X56500Y239800D02*
Y243019D01*
G01X41150Y265800D02*
X41450Y266100D01*
G01X28150Y265800D02*
X41150D01*
G01X37000Y282200D02*
X35600Y280800D01*
G01X42500Y282200D02*
X37000D01*
G01X33750Y278950D02*
X35600Y280800D01*
G01X30700Y278950D02*
X33750D01*
G01X26600D02*
X30700D01*
G01X68898Y282200D02*
X69399Y281699D01*
G01X62500Y282200D02*
X68898D01*
G01X69403Y281695D02*
X69399Y281699D01*
G01X74046Y281695D02*
X69403D01*
G01X69000Y277200D02*
X69500Y276700D01*
G01X62500Y277200D02*
X69000D01*
G01X69505Y276695D02*
X69500Y276700D01*
G01X74046Y276695D02*
X69505D01*
G01X36000Y292100D02*
X35600Y292500D01*
G01X42400Y292100D02*
X36000D01*
G01X42500Y292200D02*
X42400Y292100D01*
G01X35300Y292200D02*
X35600Y292500D01*
G01X30450Y292200D02*
X35300D01*
G01X30450Y296700D02*
Y292200D01*
G01X49320Y240620D02*
Y250280D01*
G01X45650Y241050D02*
Y250280D01*
G01X35800Y287200D02*
X35600Y287000D01*
G01X42500Y287200D02*
X35800D01*
G01X34900Y287700D02*
X35600Y287000D01*
G01X30450Y287700D02*
X34900D01*
G01X30450Y283200D02*
Y287700D01*
G01X65317Y242333D02*
X93884D01*
G01X69300Y287200D02*
X69400Y287100D01*
G01X62500Y287200D02*
X69300D01*
G01X69805Y286695D02*
X69400Y287100D01*
G01X74046Y286695D02*
X69805D01*
G01X31466Y239808D02*
X29650Y237992D01*
G01X35405Y239808D02*
X31466D01*
G01X38275Y309922D02*
X35918Y307565D01*
G01X42404Y309922D02*
X38275D01*
G01X33603Y305250D02*
X35918Y307565D01*
G01X31400Y305250D02*
X33603D01*
G01X27200D02*
X31400D01*
G01X71100Y309100D02*
X69304D01*
G01X71500Y309500D02*
X71100Y309100D01*
G01X73950Y309500D02*
X71500D01*
G01X68482Y309922D02*
X69304Y309100D01*
G01X62404Y309922D02*
X68482D01*
G01X41325Y339687D02*
Y338045D01*
G01X40336Y340676D02*
X41325Y339687D01*
G01X37376Y340676D02*
X40336D01*
G01X36145Y341907D02*
X37376Y340676D01*
G01X36145Y344207D02*
Y341907D01*
G01X41325Y338045D02*
Y334268D01*
G01X73725Y357207D02*
Y362954D01*
G01X23471Y360853D02*
X22600Y361724D01*
G01X27496Y360853D02*
X23471D01*
G01X28465Y359884D02*
X27496Y360853D01*
G01X28465Y357007D02*
Y359884D01*
G01X31025Y357007D02*
Y362734D01*
G01X66171Y361053D02*
X65300Y361924D01*
G01X70196Y361053D02*
X66171D01*
G01X71165Y360084D02*
X70196Y361053D01*
G01X71165Y357207D02*
Y360084D01*
G01X36145Y361045D02*
Y357007D01*
G01X38200Y363100D02*
X36145Y361045D01*
G01X33585Y366335D02*
Y357007D01*
G01X57145Y360703D02*
X58567Y362125D01*
G01X57145Y356807D02*
Y360703D01*
G01X62325Y339487D02*
Y337845D01*
G01X61336Y340476D02*
X62325Y339487D01*
G01X58376Y340476D02*
X61336D01*
G01X57145Y341707D02*
X58376Y340476D01*
G01X57145Y344007D02*
Y341707D01*
G01X62325Y337845D02*
Y334068D01*
G01X33585Y340485D02*
X36325Y337745D01*
G01X33585Y344207D02*
Y340485D01*
G01X37900Y336170D02*
X36325Y337745D01*
G01X37900Y334380D02*
Y336170D01*
G01X54329Y360740D02*
Y366179D01*
G01X54585Y360484D02*
X54329Y360740D01*
G01X54585Y356807D02*
Y360484D01*
G01X76285Y340375D02*
Y344407D01*
G01X78805Y337855D02*
X76285Y340375D01*
G01Y366135D02*
Y357207D01*
G01X68378Y314922D02*
X69200Y314100D01*
G01X62404Y314922D02*
X68378D01*
G01X69300Y314000D02*
X69200Y314100D01*
G01X73750Y314000D02*
X69300D01*
G01X35800D02*
X35500D01*
G01X36722Y314922D02*
X35800Y314000D01*
G01X42404Y314922D02*
X36722D01*
G01X30750Y314000D02*
X35500D01*
G01X30750Y309500D02*
Y314000D01*
G01X43600Y361524D02*
Y362649D01*
G01X44471Y360653D02*
X43600Y361524D01*
G01X48496Y360653D02*
X44471D01*
G01X49465Y359684D02*
X48496Y360653D01*
G01X49465Y356807D02*
Y359684D01*
G01X36322Y319922D02*
X35500Y319100D01*
G01X42404Y319922D02*
X36322D01*
G01X34900Y318500D02*
X35500Y319100D01*
G01X30750Y318500D02*
X34900D01*
G01X30750Y323000D02*
Y318500D01*
G01X58900Y335970D02*
X57325Y337545D01*
G01X58900Y334180D02*
Y335970D01*
G01X54585Y340285D02*
X57325Y337545D01*
G01X54585Y344007D02*
Y340285D01*
G01X52025Y356807D02*
Y362525D01*
G01X70900Y303900D02*
X69400D01*
G01X71500Y304500D02*
X70900Y303900D01*
G01X73950Y304500D02*
X71500D01*
G01X67600Y303900D02*
X69400D01*
G01X66578Y304922D02*
X67600Y303900D01*
G01X62404Y304922D02*
X66578D01*
G01X73725Y362954D02*
X72446Y364233D01*
G01X68800Y371550D02*
Y367751D01*
G01X69300Y372050D02*
X68800Y371550D01*
G01X73100Y372050D02*
X69300D01*
G01X68928Y367751D02*
X68800D01*
G01X72446Y364233D02*
X68928Y367751D01*
G01X22600Y361724D02*
Y362849D01*
G01Y367552D02*
Y362849D01*
G01Y369366D02*
Y367552D01*
G01X22000Y369966D02*
X22600Y369366D01*
G01X22000Y371602D02*
Y369966D01*
G01X60850Y399410D02*
X60830Y399390D01*
G01X60850Y403150D02*
Y399410D01*
G01X66455Y399000D02*
X64700D01*
G01X67500Y397955D02*
X66455Y399000D01*
G01X70757Y397955D02*
X67500D01*
G01X64310Y399390D02*
X64700Y399000D01*
G01X60830Y399390D02*
X64310D01*
G01X31025Y362734D02*
X29706Y364053D01*
G01X26100Y371602D02*
Y367552D01*
G01X29900Y371602D02*
X26100D01*
G01X26207Y367552D02*
X26100D01*
G01X29706Y364053D02*
X26207Y367552D01*
G01X33740Y398560D02*
X36850D01*
G01X32850Y399450D02*
X33740Y398560D01*
G01X25700Y399450D02*
X32850D01*
G01X39089Y398560D02*
X36850D01*
G01X40200Y397449D02*
X39089Y398560D01*
G01X40200Y391600D02*
Y397449D01*
G01X37500Y388900D02*
X40200Y391600D01*
G01X37500Y387450D02*
Y388900D01*
G01X25700Y405700D02*
Y399450D01*
G01X32200Y412200D02*
X25700Y405700D01*
G01X99912Y412200D02*
X32200D01*
G01X65300Y361924D02*
Y363049D01*
G01Y367751D02*
Y363049D01*
G01Y371850D02*
Y367751D01*
G01X65500Y372050D02*
X65300Y371850D01*
G01X39350Y366850D02*
X38200D01*
G01X40100Y366100D02*
X39350Y366850D01*
G01X40100Y363400D02*
Y366100D01*
G01X38200Y366850D02*
Y363100D01*
G01X35350Y366850D02*
X34100D01*
G01X35800Y366400D02*
X35350Y366850D01*
G01X35800Y363400D02*
Y366400D01*
G01X34100Y366850D02*
X33585Y366335D01*
G01X58567Y364817D02*
X60400Y366650D01*
G01X58567Y362125D02*
Y364817D01*
G01X63300Y369550D02*
X60400Y366650D01*
G01X63300Y374900D02*
Y369550D01*
G01X61300Y376900D02*
X63300Y374900D01*
G01X61300Y379800D02*
Y376900D01*
G01X62400Y380900D02*
X61300Y379800D01*
G01X79292Y380900D02*
X62400D01*
G01X31500Y396000D02*
X30400Y397100D01*
G01X36850Y396000D02*
X31500D01*
G01X27700Y397100D02*
X30400D01*
G01X26550Y395950D02*
X27700Y397100D01*
G01X25700Y395950D02*
X26550D01*
G01X25700Y391950D02*
Y395950D01*
G01X62071Y383400D02*
X72356D01*
G01X59300Y380629D02*
X62071Y383400D01*
G01X59300Y377000D02*
Y380629D01*
G01X57650Y375350D02*
X59300Y377000D01*
G01X57650Y369500D02*
Y375350D01*
G01X54800Y366650D02*
X57650Y369500D01*
G01X54329Y366179D02*
X54800Y366650D01*
G01X72356Y383400D02*
X106709D01*
G01X61100Y385600D02*
X107041D01*
G01X56460Y380960D02*
X61100Y385600D01*
G01X30140Y380960D02*
X56460D01*
G01X28200Y382900D02*
X30140Y380960D01*
G01X25700Y385400D02*
X28200Y382900D01*
G01X25700Y388450D02*
Y385400D01*
G01X39189Y383750D02*
X42076D01*
G01X38989Y383950D02*
X39189Y383750D01*
G01X37500Y383950D02*
X38989D01*
G01X45560Y393440D02*
X43350D01*
G01X46750Y392250D02*
X45560Y393440D01*
G01X46750Y387500D02*
Y392250D01*
G01X44315Y383750D02*
X42076D01*
G01X46750Y386185D02*
X44315Y383750D01*
G01X46750Y387500D02*
Y386185D01*
G01X77200Y367050D02*
X76285Y366135D01*
G01X43600Y367350D02*
Y362649D01*
G01X43650Y367400D02*
X43600Y367350D01*
G01X43650Y370833D02*
Y367400D01*
G01X43000Y371483D02*
X43650Y370833D01*
G01X52025Y362525D02*
X50486Y364064D01*
G01X46900Y367650D02*
X47150Y367400D01*
G01X46900Y371483D02*
Y367650D01*
G01X50700Y371483D02*
X46900D01*
G01X50486Y364064D02*
X47150Y367400D01*
G01X77546Y276695D02*
X80688D01*
G01X77546Y281695D02*
X80688D01*
G01X176034Y258164D02*
X133326Y300872D01*
G01X176614Y260413D02*
X135326Y301701D01*
G01X94820Y357000D02*
Y363087D01*
G01X78845Y361103D02*
Y357207D01*
G01X80267Y362525D02*
X78845Y361103D01*
G01X137326Y302530D02*
Y450090D01*
G01X177143Y262713D02*
X137326Y302530D01*
G01X87266Y360846D02*
X86395Y361717D01*
G01X91291Y360846D02*
X87266D01*
G01X92260Y359877D02*
X91291Y360846D01*
G01X92260Y357000D02*
Y359877D01*
G01X84025Y338245D02*
Y334468D01*
G01Y339887D02*
Y338245D01*
G01X83036Y340876D02*
X84025Y339887D01*
G01X80076Y340876D02*
X83036D01*
G01X78845Y342107D02*
X80076Y340876D01*
G01X78845Y344407D02*
Y342107D01*
G01X80500Y304500D02*
X80600Y304600D01*
G01X77450Y304500D02*
X80500D01*
G01X80600Y309500D02*
X80700Y309400D01*
G01X77450Y309500D02*
X80600D01*
G01X133326Y300872D02*
Y442074D01*
G01X97380Y365928D02*
Y357000D01*
G01X78805Y336375D02*
Y337855D01*
G01X80600Y334580D02*
X78805Y336375D01*
G01X99940Y341900D02*
Y344200D01*
G01X101171Y340669D02*
X99940Y341900D01*
G01X104131Y340669D02*
X101171D01*
G01X105710Y339090D02*
X104131Y340669D01*
G01X105710Y338260D02*
Y339090D01*
G01X105480Y338030D02*
X105710Y338260D01*
G01X106500Y337010D02*
Y333900D01*
G01X105480Y338030D02*
X106500Y337010D01*
G01X135326Y301701D02*
Y445311D01*
G01X99940Y360896D02*
Y357000D01*
G01X101362Y362318D02*
X99940Y360896D01*
G01X97380Y340138D02*
X100270Y337248D01*
G01X97380Y344200D02*
Y340138D01*
G01X102400Y335118D02*
X100270Y337248D01*
G01X102400Y333900D02*
Y335118D01*
G01X84526Y395395D02*
X84536Y395405D01*
G01X77257Y395395D02*
X84526D01*
G01X88845Y395405D02*
X84536D01*
G01X89600Y394650D02*
X88845Y395405D01*
G01X93700Y394650D02*
X89600D01*
G01X93150Y387600D02*
X89600Y391150D01*
G01X103916Y387600D02*
X93150D01*
G01X107582Y391266D02*
X103916Y387600D01*
G01X82106Y392835D02*
X84536Y390405D01*
G01X77257Y392835D02*
X82106D01*
G01X86805Y390405D02*
X84536D01*
G01X87550Y391150D02*
X86805Y390405D01*
G01X89600Y391150D02*
X87550D01*
G01X94820Y363087D02*
X93641Y364266D01*
G01X89895Y371676D02*
X93695D01*
G01X89895Y367626D02*
Y371676D01*
G01X90281Y367626D02*
X89895D01*
G01X93641Y364266D02*
X90281Y367626D01*
G01X98614Y391150D02*
X102679D01*
G01X93700D02*
X98614D01*
G01X82171Y366179D02*
X81300Y367050D01*
G01X82171Y363195D02*
Y366179D01*
G01X80267Y366017D02*
Y362525D01*
G01X81300Y367050D02*
X80267Y366017D01*
G01X86395Y361717D02*
Y362842D01*
G01Y367626D02*
Y362842D01*
G01Y369359D02*
Y367626D01*
G01X85795Y369959D02*
X86395Y369359D01*
G01X85795Y371676D02*
Y369959D01*
G01X104900Y412200D02*
X99912D01*
G01X109910Y380900D02*
X79292D01*
G01X112023Y383013D02*
X109910Y380900D01*
G01X99266Y365872D02*
X98295Y366843D01*
G01X99266Y362988D02*
Y365872D01*
G01X98295Y366843D02*
X97380Y365928D01*
G01X107041Y385600D02*
X112638Y391197D01*
G01X78171Y366079D02*
X77200Y367050D01*
G01X78171Y363195D02*
Y366079D01*
G01X103266Y365972D02*
X102395Y366843D01*
G01X103266Y362988D02*
Y365972D01*
G01X101362Y365810D02*
Y362318D01*
G01X102395Y366843D02*
X101362Y365810D01*
G01X118110Y480807D02*
Y489010D01*
G01X125984Y489284D02*
Y480807D01*
G01X133858Y453558D02*
Y464075D01*
G01X137326Y450090D02*
X133858Y453558D01*
G01X118110Y457290D02*
Y464075D01*
G01X133326Y442074D02*
X118110Y457290D01*
G01X125984Y454653D02*
Y464075D01*
G01X135326Y445311D02*
X125984Y454653D01*
G01X133858Y480807D02*
Y487658D01*
G01X123000Y493900D02*
X146758D01*
G01X118110Y489010D02*
X123000Y493900D01*
G01X128600Y491900D02*
X125984Y489284D01*
G01X145929Y491900D02*
X128600D01*
G01X136100Y489900D02*
X145100D01*
G01X133858Y487658D02*
X136100Y489900D01*
G01X164020Y101127D02*
Y104310D01*
G01X163550Y113400D02*
Y109050D01*
G01X171694Y125894D02*
Y128547D01*
G01X170300Y124500D02*
X171694Y125894D01*
G01X166100Y124500D02*
X170300D01*
G01X164900Y123300D02*
X166100Y124500D01*
G01X163550Y117700D02*
Y113400D01*
G01Y121950D02*
X164900Y123300D01*
G01X163550Y117700D02*
Y121950D01*
G01X291113Y274213D02*
X183901D01*
G01X179789D02*
X183901D01*
G01X153989Y300013D02*
X179789Y274213D01*
G01X151989Y299184D02*
Y485840D01*
G01X179160Y272013D02*
X151989Y299184D01*
G01X271468Y272013D02*
X179160D01*
G01X178202Y267313D02*
X267668D01*
G01X147989Y297526D02*
X178202Y267313D01*
G01X147989Y484011D02*
Y297526D01*
G01X228668Y262713D02*
X177143D01*
G01X204368Y258164D02*
X176034D01*
G01X177572Y265113D02*
X139326Y303359D01*
G01X291268Y265113D02*
X177572D01*
G01X203600Y278400D02*
X194000Y288000D01*
G01X192000Y290000D02*
Y302000D01*
G01X194000Y288000D02*
X192000Y290000D01*
G01X194200Y294000D02*
X198700Y289500D01*
G01X194200Y300000D02*
Y294000D01*
G01X198700Y289500D02*
X201250Y286950D01*
G01X216068Y260413D02*
X176614D01*
G01X178631Y269713D02*
X285268D01*
G01X149989Y298355D02*
X178631Y269713D01*
G01X149989Y485011D02*
Y298355D01*
G01X153989Y486669D02*
Y300013D01*
G01X139326Y303359D02*
Y449979D01*
G01X194000Y304000D02*
X200950D01*
G01X192000Y302000D02*
X194000Y304000D01*
G01X195900Y301700D02*
X194200Y300000D01*
G01X202500Y301700D02*
X195900D01*
G01X151989Y485840D02*
X145929Y491900D01*
G01X144300Y487700D02*
X147989Y484011D01*
G01X141732Y480807D02*
Y486932D01*
G01Y452385D02*
Y464075D01*
G01X139326Y449979D02*
X141732Y452385D01*
G01X145100Y489900D02*
X149989Y485011D01*
G01X146758Y493900D02*
X153989Y486669D01*
G01X142500Y487700D02*
X144300D01*
G01X141732Y486932D02*
X142500Y487700D01*
G01X260469Y25721D02*
X315903D01*
G01X250137Y36053D02*
X260469Y25721D01*
G01X246530Y39660D02*
X250137Y36053D01*
G01X246530Y66786D02*
Y39660D01*
G01X255250Y95000D02*
X250500D01*
G01X255250Y90000D02*
Y95000D01*
G01X248169Y94169D02*
Y87899D01*
G01X249000Y95000D02*
X248169Y94169D01*
G01X250500Y95000D02*
X249000D01*
G01X258750Y85000D02*
Y90000D01*
G01X245609Y71207D02*
X246530Y70286D01*
G01X245609Y81399D02*
Y71207D01*
G01X258750Y82944D02*
Y85000D01*
G01X257328Y81522D02*
X258750Y82944D01*
G01X252832Y81522D02*
X257328D01*
G01X251221Y79911D02*
X252832Y81522D01*
G01X251221Y74202D02*
Y79911D01*
G01X247305Y70286D02*
X251221Y74202D01*
G01X246530Y70286D02*
X247305D01*
G01X261102Y61140D02*
X253613D01*
G01X251584D02*
X253613D01*
G01X250791Y61933D02*
X251584Y61140D01*
G01X250791Y65677D02*
Y61933D01*
G01X258750Y95000D02*
X265880D01*
G01X223544Y76044D02*
Y74403D01*
G01X223549Y76049D02*
X223544Y76044D01*
G01X223549Y81399D02*
Y76049D01*
G01X223971Y70265D02*
X223995Y70241D01*
G01X220227Y70265D02*
X223971D01*
G01X223995Y72505D02*
Y70241D01*
G01X223544Y72956D02*
X223995Y72505D01*
G01X223544Y74403D02*
Y72956D01*
G01X261102Y69010D02*
X263847D01*
G01X250791Y69177D02*
X255154D01*
G01X261102Y62715D02*
X264661D01*
G01X257315Y70585D02*
X261102D01*
G01X255300Y72600D02*
X257315Y70585D01*
G01X235601Y87899D02*
X228669D01*
G01X236750Y86750D02*
X235601Y87899D01*
G01X236750Y83000D02*
Y86750D01*
G01Y71000D02*
X233750Y68000D01*
G01X236750Y83000D02*
Y71000D01*
G01X233759Y67991D02*
X233750Y68000D01*
G01X233759Y64752D02*
Y67991D01*
G01X265107Y65865D02*
X261102D01*
G01X267465Y64290D02*
X261102D01*
G01X234693Y57401D02*
X231753Y60341D01*
G01X234693Y57400D02*
Y57401D01*
G01X226109Y75891D02*
Y81399D01*
G01X227750Y74250D02*
X226109Y75891D01*
G01X227750Y73000D02*
Y74250D01*
G01Y70500D02*
X230250Y68000D01*
G01X227750Y73000D02*
Y70500D01*
G01X230250Y61843D02*
Y68000D01*
G01X231752Y60341D02*
X230250Y61843D01*
G01X231753Y60341D02*
X231752D01*
G01X242733Y78614D02*
Y74428D01*
G01X243049Y78930D02*
X242733Y78614D01*
G01X243049Y81399D02*
Y78930D01*
G01X242733Y74428D02*
Y70261D01*
G01X242682Y70312D02*
X242733Y70261D01*
G01X238880Y70312D02*
X242682D01*
G01X261102Y67435D02*
X264840D01*
G01X221800Y301038D02*
Y298800D01*
G01X214400Y288350D02*
X215300Y287450D01*
G01X214400Y292500D02*
Y288350D01*
G01X216640Y294740D02*
X214400Y292500D01*
G01X216640Y298700D02*
Y294740D01*
G01X221800Y296927D02*
Y298800D01*
G01X216400Y291527D02*
X221800Y296927D01*
G01X216400Y288550D02*
Y291527D01*
G01X215300Y287450D02*
X216400Y288550D01*
G01X232312Y292212D02*
X232300Y292200D01*
G01X232312Y298705D02*
Y292212D01*
G01X239050Y280100D02*
X234800Y284350D01*
G01X239050Y279700D02*
Y280100D01*
G01X234300Y284350D02*
X230700Y287950D01*
G01X234800Y284350D02*
X234300D01*
G01X230700Y290600D02*
X232300Y292200D01*
G01X230700Y287950D02*
Y290600D01*
G01X295537Y262713D02*
X228668D01*
G01X240200Y298400D02*
X240000Y298200D01*
G01X240200Y303350D02*
Y298400D01*
G01X235675Y287850D02*
X234800D01*
G01X236900Y289075D02*
X235675Y287850D01*
G01X236900Y295100D02*
Y289075D01*
G01X240000Y298200D02*
X236900Y295100D01*
G01X234872Y290795D02*
Y298705D01*
G01X234800Y290723D02*
X234872Y290795D01*
G01X234800Y287850D02*
Y290723D01*
G01X248095Y293695D02*
X246800Y292400D01*
G01X248095Y298667D02*
Y293695D01*
G01X244150Y289700D02*
X245800Y288050D01*
G01X242400Y289700D02*
X244150D01*
G01X245800Y291400D02*
X246800Y292400D01*
G01X245800Y288050D02*
Y291400D01*
G01X306164Y258164D02*
X204368D01*
G01X214080Y295082D02*
X211300Y292302D01*
G01X214080Y298700D02*
Y295082D01*
G01X215250Y284000D02*
X211250D01*
G01X215300Y283950D02*
X215250Y284000D01*
G01X211150Y284100D02*
X211250Y284000D01*
G01X211150Y287800D02*
Y284100D01*
G01Y292152D02*
X211300Y292302D01*
G01X211150Y287800D02*
Y292152D01*
G01X207500Y278400D02*
X203600D01*
G01X211520Y298700D02*
Y301780D01*
G01X203750Y298800D02*
Y300450D01*
G01X206062Y298800D02*
X203750D01*
G01X206162Y298700D02*
X206062Y298800D01*
G01X208960Y298700D02*
X206162D01*
G01X201250Y284449D02*
X204997Y280702D01*
G01X201250Y286950D02*
Y284449D01*
G01X216068Y260413D02*
X305584D01*
G01X258800Y300750D02*
Y296500D01*
G01X255300Y288650D02*
X256000Y287950D01*
G01X255300Y293115D02*
Y288650D01*
G01X253215Y295200D02*
X255300Y293115D01*
G01X253215Y298667D02*
Y295200D01*
G01X257800Y295500D02*
X258800Y296500D01*
G01X257800Y288700D02*
Y295500D01*
G01X257050Y287950D02*
X257800Y288700D01*
G01X256000Y287950D02*
X257050D01*
G01X250655Y293445D02*
X251800Y292300D01*
G01X250655Y298667D02*
Y293445D01*
G01X256000Y280601D02*
Y284450D01*
G01X255131Y279732D02*
X256000Y280601D01*
G01X252595Y279732D02*
X255131D01*
G01X255500Y284450D02*
X252000Y287950D01*
G01X256000Y284450D02*
X255500D01*
G01X252000Y292100D02*
X251800Y292300D01*
G01X252000Y287950D02*
Y292100D01*
G01X219400Y291000D02*
Y287450D01*
G01X220900Y292500D02*
X219400Y291000D01*
G01X223000Y294600D02*
X220900Y292500D01*
G01X225900Y294600D02*
X223000D01*
G01X227192Y295892D02*
X225900Y294600D01*
G01X227192Y298705D02*
Y295892D01*
G01X222200Y277778D02*
X222320Y277658D01*
G01X222200Y286256D02*
Y277778D01*
G01X221006Y287450D02*
X222200Y286256D01*
G01X219400Y287450D02*
X221006D01*
G01X238900Y291800D02*
Y287950D01*
G01X239700Y292600D02*
X238900Y291800D01*
G01X240500Y293400D02*
X239700Y292600D01*
G01X243000Y293400D02*
X240500D01*
G01X245535Y295935D02*
X243000Y293400D01*
G01X245535Y298667D02*
Y295935D01*
G01X240752Y287950D02*
X242402Y286300D01*
G01X238900Y287950D02*
X240752D01*
G01X262800Y285150D02*
X260000Y287950D01*
G01X263400Y292300D02*
X261600D01*
G01X260500D02*
X261600D01*
G01X260000Y291800D02*
X260500Y292300D01*
G01X260000Y287950D02*
Y291800D01*
G01X229752Y294852D02*
X227200Y292300D01*
G01X229752Y298705D02*
Y294852D01*
G01X224750Y287950D02*
X226600D01*
G01X224200Y287400D02*
X224750Y287950D01*
G01X224200Y280200D02*
Y287400D01*
G01X225500Y278900D02*
X224200Y280200D01*
G01X226600Y291700D02*
X227200Y292300D01*
G01X226600Y287950D02*
Y291700D01*
G01X222000Y301238D02*
X221800Y301038D01*
G01X222000Y303250D02*
Y301238D01*
G01X259690Y322676D02*
Y320875D01*
G01X261365Y324351D02*
X259690Y322676D01*
G01X261739Y315715D02*
X264114D01*
G01X259690Y317764D02*
X261739Y315715D01*
G01X259690Y320875D02*
Y317764D01*
G01X263804Y326227D02*
X253154D01*
G01X207150Y303400D02*
X203750Y306800D01*
G01X209900Y303400D02*
X207150D01*
G01X211520Y301780D02*
X209900Y303400D01*
G01X200950Y304000D02*
X203750Y306800D01*
G01Y300450D02*
X202500Y301700D01*
G01X242091Y317985D02*
Y327293D01*
G01X245535Y314541D02*
X242091Y317985D01*
G01X245535Y311467D02*
Y314541D01*
G01X242091Y328181D02*
Y327293D01*
G01X243610Y329700D02*
X242091Y328181D01*
G01X246100Y329700D02*
X243610D01*
G01X258700Y300850D02*
X258800Y300750D01*
G01X245943Y326300D02*
Y322043D01*
G01Y316962D02*
Y322043D01*
G01X248095Y314810D02*
X245943Y316962D01*
G01X248095Y311467D02*
Y314810D01*
G01X227192Y314408D02*
Y311505D01*
G01X224500Y317100D02*
X227192Y314408D01*
G01X224500Y325500D02*
Y317100D01*
G01X226500Y327500D02*
X224500Y325500D01*
G01X228600Y329600D02*
X230400D01*
G01X226500Y327500D02*
X228600Y329600D01*
G01X208960Y322460D02*
Y318800D01*
G01X216500Y330000D02*
X208960Y322460D01*
G01X218300Y330000D02*
X216500D01*
G01X208960Y318800D02*
Y311500D01*
G01X216600Y326600D02*
X218400D01*
G01X214200Y324200D02*
X216600Y326600D01*
G01X211520Y321520D02*
X214200Y324200D01*
G01X211520Y311500D02*
Y321520D01*
G01X263531Y329698D02*
X253245D01*
G01X227500Y317360D02*
Y318900D01*
G01X229752Y315108D02*
X227500Y317360D01*
G01X229752Y311505D02*
Y315108D01*
G01X227500Y320200D02*
Y318900D01*
G01X230400Y323100D02*
X227500Y320200D01*
G01X230400Y326200D02*
Y323100D01*
G01X259800Y420350D02*
X259750Y420300D01*
G01X259800Y423400D02*
Y420350D01*
G01X259750Y412100D02*
Y420300D01*
G01X257776Y407526D02*
Y405313D01*
G01X259750Y409500D02*
X257776Y407526D01*
G01X259750Y412100D02*
Y409500D01*
G01X319316Y29134D02*
X338583D01*
G01X315903Y25721D02*
X319316Y29134D01*
G01X277750Y42500D02*
X286848D01*
G01X289564D02*
X302591Y55527D01*
G01X286848Y42500D02*
X289564D01*
G01X290913Y29000D02*
X283223D01*
G01X308591Y46678D02*
X290913Y29000D01*
G01X308591Y68928D02*
Y46678D01*
G01X283223Y29000D02*
X277750D01*
G01X311182Y53110D02*
X329646Y34646D01*
G01X277750Y33500D02*
X287963D01*
G01X306591Y49206D02*
Y71074D01*
G01X290885Y33500D02*
X306591Y49206D01*
G01X287963Y33500D02*
X290885D01*
G01X277750Y38000D02*
X283173D01*
G01X289939D02*
X304591Y52652D01*
G01X283173Y38000D02*
X289939D01*
G01X273273Y100227D02*
X279385D01*
G01X273250Y100250D02*
X273273Y100227D01*
G01X271130Y100250D02*
X273250D01*
G01X265880Y95000D02*
X271130Y100250D01*
G01X287129Y61140D02*
X283302D01*
G01X287469Y60800D02*
X287129Y61140D01*
G01X294644Y60800D02*
X287469D01*
G01X300311D02*
X294644D01*
G01X305061Y100227D02*
X306595Y98693D01*
G01X295385Y100227D02*
X305061D01*
G01X316788Y88500D02*
X306595Y98693D01*
G01X456818Y88500D02*
X316788D01*
G01X287227Y108227D02*
X292385D01*
G01X281235Y102235D02*
X287227Y108227D01*
G01X281235Y98693D02*
Y102235D01*
G01X280511Y97969D02*
X281235Y98693D01*
G01X272094Y97969D02*
X280511D01*
G01X266618Y92493D02*
X272094Y97969D01*
G01X266618Y72042D02*
Y92493D01*
G01X264752Y70176D02*
X266618Y72042D01*
G01X264752Y69915D02*
Y70176D01*
G01X263847Y69010D02*
X264752Y69915D01*
G01X325185Y105921D02*
X323484D01*
G01X320935D02*
X318773Y108083D01*
G01X323484Y105921D02*
X320935D01*
G01X291600Y62800D02*
X294822Y66022D01*
G01X287322Y62800D02*
X291600D01*
G01X287237Y62715D02*
X287322Y62800D01*
G01X283302Y62715D02*
X287237D01*
G01X300581Y71781D02*
X294822Y66022D01*
G01X300581Y76875D02*
Y71781D01*
G01X306280Y82574D02*
X300581Y76875D01*
G01X278039Y72035D02*
Y82185D01*
G01X268147Y62143D02*
X278039Y72035D01*
G01X265233Y62143D02*
X268147D01*
G01X264661Y62715D02*
X265233Y62143D01*
G01X303075Y93239D02*
X296092D01*
G01X313814Y82500D02*
X303075Y93239D01*
G01X453500Y82500D02*
X313814D01*
G01X283385Y99014D02*
Y100227D01*
G01X289160Y93239D02*
X283385Y99014D01*
G01X296092Y93239D02*
X289160D01*
G01X271864Y84789D02*
Y82126D01*
G01X272937Y85862D02*
X271864Y84789D01*
G01X265532Y66290D02*
X265107Y65865D01*
G01X266636Y66290D02*
X265532D01*
G01X271864Y71518D02*
X266636Y66290D01*
G01X271864Y82126D02*
Y71518D01*
G01X302591Y71074D02*
X304591Y73074D01*
G01X302591Y55527D02*
Y71074D01*
G01X308710Y104812D02*
Y114611D01*
G01X320822Y92700D02*
X308710Y104812D01*
G01X462559Y92700D02*
X320822D01*
G01X320398Y100053D02*
X315932Y104519D01*
G01X461764Y100053D02*
X320398D01*
G01X314772Y105679D02*
Y108292D01*
G01X315932Y104519D02*
X314772Y105679D01*
G01X289793Y70587D02*
Y85901D01*
G01X286641Y67435D02*
X289793Y70587D01*
G01X283302Y67435D02*
X286641D01*
G01X289793Y88337D02*
X292030Y90574D01*
G01X289793Y85901D02*
Y88337D01*
G01X291970Y69137D02*
Y76090D01*
G01X289887Y67054D02*
X291970Y69137D01*
G01X287970Y67054D02*
X289887D01*
G01X286781Y65865D02*
X287970Y67054D01*
G01X283302Y65865D02*
X286781D01*
G01X291970Y78264D02*
X296280Y82574D01*
G01X291970Y76090D02*
Y78264D01*
G01X318865Y90700D02*
X461730D01*
G01X306196Y103369D02*
X318865Y90700D01*
G01X306196Y106297D02*
Y103369D01*
G01Y110209D02*
Y106297D01*
G01X283393Y92324D02*
Y92325D01*
G01X279615Y88546D02*
X283393Y92324D01*
G01X274195Y71020D02*
X267465Y64290D01*
G01X274195Y71021D02*
Y71020D01*
G01X274510Y71336D02*
X274195Y71021D01*
G01X274510Y83441D02*
Y71336D01*
G01X279615Y88546D02*
X274510Y83441D01*
G01X322705Y108071D02*
X313051Y117725D01*
G01X325864Y108071D02*
X322705D01*
G01X311182Y58692D02*
Y53110D01*
G01X279010Y69010D02*
X283302D01*
G01X276700Y66700D02*
X279010Y69010D01*
G01X311293Y106117D02*
Y109977D01*
G01X319357Y98053D02*
X311293Y106117D01*
G01X460935Y98053D02*
X319357D01*
G01X311293Y113238D02*
X310711Y113820D01*
G01X311293Y109977D02*
Y113238D01*
G01X316772Y111099D02*
X310200Y117671D01*
G01X316772Y107255D02*
Y111099D01*
G01X321974Y102053D02*
X316772Y107255D01*
G01X462593Y102053D02*
X321974D01*
G01X287385Y98828D02*
X289398Y96815D01*
G01X287385Y100227D02*
Y98828D01*
G01X314857Y84500D02*
X454400D01*
G01X303877Y95480D02*
X314857Y84500D01*
G01X290733Y95480D02*
X303877D01*
G01X289398Y96815D02*
X290733Y95480D01*
G01X299885Y107727D02*
X300385Y108227D01*
G01X299885Y104177D02*
Y107727D01*
G01X301403Y104177D02*
X299885D01*
G01X302500Y105274D02*
X301403Y104177D01*
G01X302500Y115000D02*
Y105274D01*
G01X268962Y71557D02*
Y88452D01*
G01X264840Y67435D02*
X268962Y71557D01*
G01X272510Y95556D02*
X280298D01*
G01X268962Y92008D02*
X272510Y95556D01*
G01X268962Y88452D02*
Y92008D01*
G01X306591Y71074D02*
X308591Y73074D01*
G01X323746Y110071D02*
X322470Y111347D01*
G01X468781Y110071D02*
X323746D01*
G01X322470Y111347D02*
X319534Y114283D01*
G01X304591Y52652D02*
Y68928D01*
G01X293679Y97933D02*
X300168D01*
G01X291385Y100227D02*
X293679Y97933D01*
G01X304253D02*
X300168D01*
G01X315686Y86500D02*
X304253Y97933D01*
G01X457647Y86500D02*
X315686D01*
G01X287292Y64290D02*
X283302D01*
G01X287802Y64800D02*
X287292Y64290D01*
G01X290495Y64800D02*
X287802D01*
G01X294914Y69219D02*
X290495Y64800D01*
G01X294914Y71626D02*
Y69219D01*
G01Y76208D02*
X301280Y82574D01*
G01X294914Y71626D02*
Y76208D01*
G01X321051Y134028D02*
X327500D01*
G01X321696Y130555D02*
X475761D01*
G01X321696Y130554D02*
Y130555D01*
G01X319051Y133199D02*
X321696Y130554D01*
G01X319051Y134857D02*
Y133199D01*
G01X319851Y135657D02*
X319051Y134857D01*
G01X319851Y228851D02*
Y135657D01*
G01X324026Y115936D02*
X327891Y112071D01*
G01X308710Y114611D02*
X307369Y115952D01*
G01D02*
X304529Y118792D01*
G01X319726Y119786D02*
X332236D01*
G01X317051Y122461D02*
X319726Y119786D01*
G01X317051Y135686D02*
Y122461D01*
G01X317851Y136486D02*
X317051Y135686D01*
G01X317851Y231351D02*
Y136486D01*
G01X313851Y138144D02*
Y235795D01*
G01X313051Y137344D02*
X313851Y138144D01*
G01X313051Y117725D02*
Y137344D01*
G01X318714Y117786D02*
X331407D01*
G01X315051Y121449D02*
X318714Y117786D01*
G01X315051Y136515D02*
Y121449D01*
G01X315851Y137315D02*
X315051Y136515D01*
G01X315851Y233771D02*
Y137315D01*
G01X311851Y139451D02*
Y238028D01*
G01X310200Y137800D02*
X311851Y139451D01*
G01X310200Y117671D02*
Y137800D01*
G01X321343Y122343D02*
X326632D01*
G01X319534Y114283D02*
X319533D01*
G01X323884Y204781D02*
X332064Y196601D01*
G01X323884Y225884D02*
Y204781D01*
G01X329685Y231685D02*
X323884Y225884D01*
G01X327300Y236300D02*
X319851Y228851D01*
G01X324802Y238302D02*
X317851Y231351D01*
G01X313851Y235795D02*
X320712Y242656D01*
G01X320628Y238548D02*
X315851Y233771D01*
G01X321884Y202918D02*
X354782Y170020D01*
G01X321884Y227384D02*
Y202918D01*
G01X328335Y233835D02*
X321884Y227384D01*
G01X287214Y284440D02*
Y288167D01*
G01X288393Y283261D02*
X287214Y284440D01*
G01X289817Y283261D02*
X288393D01*
G01X291271D02*
X289817D01*
G01X292225Y284215D02*
X291271Y283261D01*
G01X292225Y288267D02*
Y284215D01*
G01X292700Y275800D02*
X291113Y274213D01*
G01X303691Y275800D02*
X292700D01*
G01X314492Y286601D02*
X303691Y275800D01*
G01X317394Y286601D02*
X314492D01*
G01X317395Y286600D02*
X317394Y286601D01*
G01X328350Y286600D02*
X317395D01*
G01X322650Y266231D02*
X326139D01*
G01X294708Y297261D02*
Y295576D01*
G01X292378Y299591D02*
X294708Y297261D01*
G01X292378Y304389D02*
Y299591D01*
G01X291384Y296534D02*
X289056D01*
G01X292342Y295576D02*
X291384Y296534D01*
G01X294708Y295576D02*
X292342D01*
G01X288536Y297054D02*
X289056Y296534D01*
G01X288536Y314764D02*
Y297054D01*
G01X326460Y269381D02*
X322650D01*
G01X316566Y284600D02*
X327521D01*
G01X316565Y284601D02*
X316566Y284600D01*
G01X315321Y284601D02*
X316565D01*
G01X304520Y273800D02*
X315321Y284601D01*
G01X293741Y273800D02*
X304520D01*
G01X291954Y272013D02*
X293741Y273800D01*
G01X271468Y272013D02*
X291954D01*
G01X294237Y267313D02*
X267668D01*
G01X296724Y269800D02*
X294237Y267313D01*
G01X306222Y269800D02*
X296724D01*
G01X317122Y280700D02*
X306222Y269800D01*
G01X325763Y280700D02*
X317122D01*
G01X322650Y275676D02*
X326076D01*
G01X298624Y265800D02*
X295537Y262713D01*
G01X308050Y265800D02*
X298624D01*
G01X313201Y270951D02*
X308050Y265800D01*
G01X322650Y270951D02*
X313201D01*
G01X326236Y247750D02*
X323900D01*
G01X283095Y291667D02*
X282362Y292400D01*
G01X287214Y291667D02*
X283095D01*
G01X281956Y292806D02*
Y297434D01*
G01X282362Y292400D02*
X281956Y292806D01*
G01X281938Y297452D02*
Y304389D01*
G01X281956Y297434D02*
X281938Y297452D01*
G01X280087Y281980D02*
Y283473D01*
G01X283491Y278576D02*
X280087Y281980D01*
G01X277750Y287950D02*
X275600D01*
G01X280087Y285613D02*
X277750Y287950D01*
G01X280087Y283473D02*
Y285613D01*
G01X272637Y295164D02*
Y298956D01*
G01X275600Y292201D02*
X272637Y295164D01*
G01X275600Y287950D02*
Y292201D01*
G01X265650Y287950D02*
X267600D01*
G01X264850Y287150D02*
X265650Y287950D01*
G01X264850Y280708D02*
Y287150D01*
G01X266406Y279152D02*
X264850Y280708D01*
G01X266406Y277835D02*
Y279152D01*
G01X267517Y293217D02*
X266600Y292300D01*
G01X267517Y298956D02*
Y293217D01*
G01X267600Y291300D02*
Y287950D01*
G01X266600Y292300D02*
X267600Y291300D01*
G01X279378Y298356D02*
Y304389D01*
G01X278456Y297434D02*
X279378Y298356D01*
G01X277300Y298590D02*
Y302800D01*
G01X278456Y297434D02*
X277300Y298590D01*
G01X312656Y264656D02*
X306164Y258164D01*
G01X322650Y264656D02*
X312656D01*
G01X297135Y294503D02*
X294708Y292076D01*
G01X297135Y297663D02*
Y294503D01*
G01X294938Y299860D02*
X297135Y297663D01*
G01X297960Y285034D02*
X297038Y285956D01*
G01X297960Y281122D02*
Y285034D01*
G01X294708Y288286D02*
X297038Y285956D01*
G01X294708Y292076D02*
Y288286D01*
G01X319451Y274101D02*
X322650D01*
G01X318301Y272951D02*
X319451Y274101D01*
G01X312372Y272951D02*
X318301D01*
G01X312321Y272900D02*
X312372Y272951D01*
G01X312300Y272900D02*
X312321D01*
G01X307200Y267800D02*
X312300Y272900D01*
G01X297553Y267800D02*
X307200D01*
G01X294866Y265113D02*
X297553Y267800D01*
G01X291268Y265113D02*
X294866D01*
G01X313650Y299700D02*
X315645Y301695D01*
G01X313650Y298850D02*
Y299700D01*
G01Y297800D02*
Y298850D01*
G01X314800Y296650D02*
X313650Y297800D01*
G01X318050Y296650D02*
X314800D01*
G01X312977Y267806D02*
X322650D01*
G01X305584Y260413D02*
X312977Y267806D01*
G01X301460Y286825D02*
X299635Y288650D01*
G01X301460Y281122D02*
Y286825D01*
G01X292713Y269713D02*
X285268D01*
G01X294800Y271800D02*
X292713Y269713D01*
G01X305349Y271800D02*
X294800D01*
G01X316149Y282600D02*
X305349Y271800D01*
G01X326692Y282600D02*
X316149D01*
G01X322650Y272526D02*
X326776D01*
G01X320712Y242656D02*
X338456D01*
G01X322532Y240452D02*
X320628Y238548D01*
G01X340352Y240452D02*
X322532D01*
G01X270077Y294323D02*
X271800Y292600D01*
G01X270077Y298956D02*
Y294323D01*
G01X275600Y283301D02*
Y284450D01*
G01X279076Y279825D02*
X275600Y283301D01*
G01X279076Y278333D02*
Y279825D01*
G01X272100Y287950D02*
X271600D01*
G01X275600Y284450D02*
X272100Y287950D01*
G01X271600Y290131D02*
Y287950D01*
G01X271800Y290331D02*
X271600Y290131D01*
G01X271800Y292600D02*
Y290331D01*
G01X311851Y238028D02*
X316847Y243024D01*
G01X318622Y244799D02*
X316847Y243024D01*
G01X334940Y244799D02*
X318622D01*
G01X324459Y297383D02*
X325611Y296231D01*
G01X324459Y301695D02*
Y297383D01*
G01X262800Y277835D02*
Y285150D01*
G01X264957Y293857D02*
X263400Y292300D01*
G01X264957Y298956D02*
Y293857D01*
G01X323950Y255300D02*
Y255200D01*
G01X327966Y259316D02*
X323950Y255300D01*
G01X323900Y255150D02*
X323950Y255200D01*
G01X323900Y251250D02*
Y255150D01*
G01X285400Y330301D02*
Y326792D01*
G01X283701Y332000D02*
X285400Y330301D01*
G01X281150Y332000D02*
X283701D01*
G01X285400Y326792D02*
Y320850D01*
G01X294950Y321700D02*
Y317400D01*
G01X292378Y314478D02*
Y310889D01*
G01X294950Y317050D02*
X292378Y314478D01*
G01X294950Y317400D02*
Y317050D01*
G01X265365Y317403D02*
Y320651D01*
G01X267517Y315251D02*
X265365Y317403D01*
G01X267517Y311756D02*
Y315251D01*
G01X265365Y320651D02*
Y324351D01*
G01X287274Y317350D02*
X285400D01*
G01X288000Y318076D02*
X287274Y317350D01*
G01X288000Y329100D02*
Y318076D01*
G01X289400Y330500D02*
X288000Y329100D01*
G01X298200Y330500D02*
X289400D01*
G01X299100Y329600D02*
X298200Y330500D01*
G01X299100Y324500D02*
Y329600D01*
G01X297498Y314798D02*
Y310889D01*
G01X299100Y316400D02*
X297498Y314798D01*
G01X299100Y324500D02*
Y316400D01*
G01X284498Y314198D02*
Y310889D01*
G01X285400Y315100D02*
X284498Y314198D01*
G01X285400Y317350D02*
Y315100D01*
G01X264957Y314872D02*
Y311756D01*
G01X264114Y315715D02*
X264957Y314872D01*
G01X299791Y352123D02*
X317195Y369527D01*
G01X276970Y339393D02*
X263804Y326227D01*
G01X287061Y339393D02*
X276970D01*
G01X299791Y352123D02*
X287061Y339393D01*
G01X275696Y304404D02*
Y314340D01*
G01X277300Y302800D02*
X275696Y304404D01*
G01X294938Y304389D02*
Y299860D01*
G01X315645Y301695D02*
X318459D01*
G01X279378Y314122D02*
Y310889D01*
G01X277250Y316250D02*
X279378Y314122D01*
G01X277250Y317700D02*
Y316250D01*
G01Y321600D02*
Y317700D01*
G01X275226Y341393D02*
X263531Y329698D01*
G01X285943Y341393D02*
X275226D01*
G01X318654Y374104D02*
X285943Y341393D01*
G01X265191Y365309D02*
X266500Y364000D01*
G01X265191Y370641D02*
Y365309D01*
G01X265250Y370700D02*
X265191Y370641D01*
G01X317195Y369527D02*
X475523D01*
G01X323468Y405044D02*
X323448Y405064D01*
G01X326588Y405044D02*
X323468D01*
G01X482705Y374104D02*
X318654D01*
G01X269500Y422865D02*
X268004Y424361D01*
G01X269500Y420250D02*
Y422865D01*
G01X329646Y34646D02*
X338583D01*
G01X328711Y108053D02*
X467756D01*
G01X327053Y104053D02*
X325185Y105921D01*
G01X464850Y104053D02*
X327053D01*
G01X327891Y112071D02*
X469822D01*
G01X327882Y106053D02*
X325864Y108071D01*
G01X465679Y106053D02*
X327882D01*
G01X369335Y143844D02*
X480287D01*
G01X360782Y152397D02*
X369335Y143844D01*
G01X360782Y172507D02*
Y152397D01*
G01X357853Y175436D02*
X360782Y172507D01*
G01X334631Y132555D02*
X476590D01*
G01X333158Y134028D02*
X334631Y132555D01*
G01X327500Y134028D02*
X333158D01*
G01X358782Y171678D02*
X354143Y176317D01*
G01X358782Y151568D02*
Y171678D01*
G01X368656Y141694D02*
X358782Y151568D01*
G01X479395Y141694D02*
X368656D01*
G01X359000Y135000D02*
X476974D01*
G01X354222D02*
X359000D01*
G01X353722Y135500D02*
X354222Y135000D01*
G01X353722Y135761D02*
Y135500D01*
G01X344434Y145049D02*
X353722Y135761D01*
G01X341913Y145049D02*
X344434D01*
G01X331649Y126073D02*
Y126111D01*
G01X335577Y122145D02*
X331649Y126073D01*
G01X474743Y122145D02*
X335577D01*
G01X333951Y118071D02*
X472737D01*
G01X332236Y119786D02*
X333951Y118071D01*
G01X333122Y116071D02*
X471908D01*
G01X331407Y117786D02*
X333122Y116071D01*
G01X367148Y137544D02*
X477259D01*
G01X354781Y149911D02*
X367148Y137544D01*
G01X354781Y151567D02*
Y149911D01*
G01X354782Y151568D02*
X354781Y151567D01*
G01X354782Y170020D02*
Y151568D01*
G01X334780Y120071D02*
X473566D01*
G01X332508Y122343D02*
X334780Y120071D01*
G01X326632Y122343D02*
X332508D01*
G01X328929Y114071D02*
X470865D01*
G01X328600Y114400D02*
X328929Y114071D01*
G01X341366Y126555D02*
X339049Y124238D01*
G01X473375Y126555D02*
X341366D01*
G01X338430Y128555D02*
X474719D01*
G01X335994Y126119D02*
X338430Y128555D01*
G01X356782Y170849D02*
X351723Y175908D01*
G01X356782Y150739D02*
Y170849D01*
G01X367977Y139544D02*
X356782Y150739D01*
G01X478503Y139544D02*
X367977D01*
G01X370780Y192318D02*
X387107D01*
G01X368558Y194540D02*
X370780Y192318D01*
G01X357853Y179953D02*
Y175436D01*
G01X362260Y184360D02*
X357853Y179953D01*
G01X354143Y176317D02*
Y183439D01*
G01X372802Y198798D02*
X389114D01*
G01X372223Y198219D02*
X372802Y198798D01*
G01X370570Y198219D02*
X372223D01*
G01X381449Y188250D02*
X421420Y148279D01*
G01X367114Y188250D02*
X381449D01*
G01X358763Y196601D02*
X367114Y188250D01*
G01X332064Y196601D02*
X358763D01*
G01X346491Y231685D02*
X329685D01*
G01X352995Y238189D02*
X346491Y231685D01*
G01X384121Y190250D02*
X423785Y150586D01*
G01X368004Y190250D02*
X384121D01*
G01X366460Y191794D02*
X368004Y190250D01*
G01X344000Y236300D02*
X327300D01*
G01X350200Y242500D02*
X344000Y236300D01*
G01X379415Y194608D02*
X387646D01*
G01X349822Y217090D02*
X348597D01*
G01X351012Y215900D02*
X349822Y217090D01*
G01X353000Y215900D02*
X351012D01*
G01X363478Y226378D02*
X353000Y215900D01*
G01X391732Y226378D02*
X363478D01*
G01X343276Y219461D02*
X341757D01*
G01X345647Y217090D02*
X343276Y219461D01*
G01X348597Y217090D02*
X345647D01*
G01X345240Y233835D02*
X328335D01*
G01X350303Y238898D02*
X345240Y233835D01*
G01X380961Y185697D02*
X420529Y146129D01*
G01X366838Y185697D02*
X380961D01*
G01X364169Y188366D02*
X366838Y185697D01*
G01X378586Y196608D02*
X388475D01*
G01X378112Y196134D02*
X378586Y196608D01*
G01X369794Y196134D02*
X378112D01*
G01X366587Y199341D02*
X369794Y196134D01*
G01X332153Y199341D02*
X366587D01*
G01X325884Y205610D02*
X332153Y199341D01*
G01X325884Y223074D02*
Y205610D01*
G01X332495Y229685D02*
X325884Y223074D01*
G01X347320Y229685D02*
X332495D01*
G01X353565Y235930D02*
X347320Y229685D01*
G01X382372Y235930D02*
X353565D01*
G01X384802Y233500D02*
X382372Y235930D01*
G01X389430Y233500D02*
X384802D01*
G01X335701Y211490D02*
Y215563D01*
G01X338603Y208588D02*
X335701Y211490D01*
G01X342856Y208588D02*
X338603D01*
G01X343858Y209590D02*
X342856Y208588D01*
G01X344891Y209590D02*
X343858D01*
G01X348597D02*
X344891D01*
G01X351723Y175908D02*
Y178499D01*
G01X332812Y201511D02*
X389230D01*
G01X327884Y206439D02*
X332812Y201511D01*
G01X327884Y222245D02*
Y206439D01*
G01X333324Y227685D02*
X327884Y222245D01*
G01X348371Y227685D02*
X333324D01*
G01X354466Y233780D02*
X348371Y227685D01*
G01X381474Y233780D02*
X354466D01*
G01X383954Y231300D02*
X381474Y233780D01*
G01X389900Y231300D02*
X383954D01*
G01X364307Y224378D02*
X393669D01*
G01X353829Y213900D02*
X364307Y224378D01*
G01X350632Y213900D02*
X353829D01*
G01X349822Y213090D02*
X350632Y213900D01*
G01X348597Y213090D02*
X349822D01*
G01X341931Y266231D02*
X344850D01*
G01X337500Y261800D02*
X341931Y266231D01*
G01X337500Y257406D02*
Y261800D01*
G01X338054Y256852D02*
X337500Y257406D01*
G01X338206Y256700D02*
X341998D01*
G01X338054Y256852D02*
X338206Y256700D01*
G01X333150Y281800D02*
X328350Y286600D01*
G01X333150Y273242D02*
Y281800D01*
G01X326139Y266231D02*
X333150Y273242D01*
G01X331150Y274071D02*
X326460Y269381D01*
G01X331150Y280971D02*
Y274071D01*
G01X327521Y284600D02*
X331150Y280971D01*
G01X326850Y279613D02*
X325763Y280700D01*
G01X326850Y276450D02*
Y279613D01*
G01X326076Y275676D02*
X326850Y276450D01*
G01X382900Y283900D02*
X377500D01*
G01X384600Y285600D02*
X382900Y283900D01*
G01X377500D02*
X372550D01*
G01X367950Y257959D02*
X365387D01*
G01X368610Y257299D02*
X367950Y257959D01*
G01X351344Y264656D02*
X353500Y262500D01*
G01X344850Y264656D02*
X351344D01*
G01X358041Y257959D02*
X353500Y262500D01*
G01X365387Y257959D02*
X358041D01*
G01X339765Y274101D02*
X332000Y266336D01*
G01X344850Y274101D02*
X339765D01*
G01X391732Y238189D02*
X352995D01*
G01X328134Y249648D02*
X326236Y247750D01*
G01X328134Y252720D02*
Y249648D01*
G01X340831Y269381D02*
X344850D01*
G01X337500Y266050D02*
X340831Y269381D01*
G01X355700Y242500D02*
X350200D01*
G01X355700D02*
X389006D01*
G01X333054Y255166D02*
Y256852D01*
G01X334455Y253765D02*
X333054Y255166D01*
G01X340280Y253765D02*
X334455D01*
G01X333054Y259939D02*
Y256852D01*
G01X334500Y261385D02*
X333054Y259939D01*
G01X334500Y266000D02*
Y261385D01*
G01X339451Y270951D02*
X334500Y266000D01*
G01X344850Y270951D02*
X339451D01*
G01X366250Y299200D02*
X370750D01*
G01X373301Y296649D02*
X370750Y299200D01*
G01X375149Y296649D02*
X373301D01*
G01X377285Y298785D02*
X375149Y296649D01*
G01X379257Y298785D02*
X377285D01*
G01X379715D02*
X379257D01*
G01X382000Y296500D02*
X379715Y298785D01*
G01X328950Y280342D02*
X326692Y282600D01*
G01X328950Y274700D02*
Y280342D01*
G01X326776Y272526D02*
X328950Y274700D01*
G01X342202Y238302D02*
X324802D01*
G01X349700Y245800D02*
X342202Y238302D01*
G01X361800Y245800D02*
X349700D01*
G01X365070Y244500D02*
X394106D01*
G01X363770Y245800D02*
X365070Y244500D01*
G01X361800Y245800D02*
X363770D01*
G01X386100Y250900D02*
X388550Y248450D01*
G01X346700Y250900D02*
X386100D01*
G01X344600Y248800D02*
X346700Y250900D01*
G01X338456Y242656D02*
X344600Y248800D01*
G01X348800Y248900D02*
X340352Y240452D01*
G01X385600Y248900D02*
X348800D01*
G01X388437Y246063D02*
X385600Y248900D01*
G01X351609Y240204D02*
X350303Y238898D01*
G01X393747Y240204D02*
X351609D01*
G01X375654Y257830D02*
X372119D01*
G01X376633Y256851D02*
X375654Y257830D01*
G01X355799Y254900D02*
X353556Y257143D01*
G01X369189Y254900D02*
X355799D01*
G01X372119Y257830D02*
X369189Y254900D01*
G01X347618Y263081D02*
X353556Y257143D01*
G01X344850Y263081D02*
X347618D01*
G01X332750Y296855D02*
Y301077D01*
G01X343041Y252900D02*
X334940Y244799D01*
G01X386241Y252900D02*
X343041D01*
G01X389141Y250000D02*
X386241Y252900D01*
G01X358096Y264704D02*
X356500Y266300D01*
G01X358096Y262268D02*
Y264704D01*
G01X354994Y267806D02*
X344850D01*
G01X356500Y266300D02*
X354994Y267806D01*
G01X338947Y294283D02*
X340250Y292980D01*
G01X327559Y294283D02*
X338947D01*
G01X325611Y296231D02*
X327559Y294283D01*
G01X376633Y263542D02*
Y261543D01*
G01X374513Y265662D02*
X376633Y263542D01*
G01X373175Y267000D02*
X374513Y265662D01*
G01X359000Y267000D02*
X373175D01*
G01X353474Y272526D02*
X359000Y267000D01*
G01X344850Y272526D02*
X353474D01*
G01X374050Y289500D02*
X372550Y288000D01*
G01X377000Y289500D02*
X374050D01*
G01X378300D02*
X380400Y287400D01*
G01X377000Y289500D02*
X378300D01*
G01X327966Y265229D02*
Y259316D01*
G01X338413Y275676D02*
X327966Y265229D01*
G01X344850Y275676D02*
X338413D01*
G01X377500Y276500D02*
Y277500D01*
G01X376500Y275500D02*
X377500Y276500D01*
G01X372750Y275500D02*
X376500D01*
G01X377500Y278500D02*
Y277500D01*
G01X376500Y279500D02*
X377500Y278500D01*
G01X372750Y279500D02*
X376500D01*
G01X372700Y275450D02*
X372750Y275500D01*
G01X372700Y273650D02*
Y275450D01*
G01X373750Y272600D02*
X372700Y273650D01*
G01X379000Y272600D02*
X373750D01*
G01X366250Y293000D02*
X371437D01*
G01X382400D02*
X384300Y291100D01*
G01X371437Y293000D02*
X382400D01*
G01X361990Y325590D02*
X360300Y323900D01*
G01X364596Y325590D02*
X361990D01*
G01X366410D02*
X364596D01*
G01X368250Y323750D02*
X366410Y325590D01*
G01X370932Y323750D02*
X368250D01*
G01X370932D02*
Y328503D01*
G01X374250Y344500D02*
Y347600D01*
G01X384000Y344500D02*
X374250D01*
G01X340500Y309823D02*
X335882D01*
G01X369890Y319208D02*
X370932Y320250D01*
G01X366807Y319208D02*
X369890D01*
G01X366042Y318443D02*
X366807Y319208D01*
G01X363400Y315801D02*
X366042Y318443D01*
G01X363400Y315800D02*
Y315801D01*
G01X361750Y339500D02*
X364050Y337200D01*
G01X361750Y340500D02*
Y339500D01*
G01Y340500D02*
X370750D01*
G01X361277Y313723D02*
X359200Y315800D01*
G01X361277Y312654D02*
Y313723D01*
G01X356623Y308000D02*
X357895Y309272D01*
G01X353250Y308000D02*
X356623D01*
G01X357895Y309272D02*
X361277Y312654D01*
G01X374050Y306500D02*
X378500D01*
G01X370750Y303200D02*
X374050Y306500D01*
G01X370750Y303200D02*
X366250D01*
G01X381396Y305500D02*
Y302610D01*
G01X380396Y306500D02*
X381396Y305500D01*
G01X378500Y306500D02*
X380396D01*
G01X348783Y319717D02*
X348900Y319600D01*
G01X345141Y319717D02*
X348783D01*
G01X348900Y317000D02*
X347750Y315850D01*
G01X348900Y319600D02*
Y317000D01*
G01X350750Y347500D02*
Y343000D01*
G01Y339404D02*
X348596Y337250D01*
G01X350750Y343000D02*
Y339404D01*
G01X352396Y336042D02*
X350298Y333944D01*
G01X352396Y337200D02*
Y336042D01*
G01X347854Y331500D02*
X350298Y333944D01*
G01X345121Y331500D02*
X347854D01*
G01X381437Y309672D02*
X385887Y305222D01*
G01X362672Y309672D02*
X381437D01*
G01X358750Y305750D02*
X362672Y309672D01*
G01X343000Y305750D02*
X358750D01*
G01X332750Y301077D02*
X334735Y303062D01*
G01X337423Y305750D02*
X343000D01*
G01X334735Y303062D02*
X337423Y305750D01*
G01X349750Y312103D02*
X351341Y313694D01*
G01X349750Y308000D02*
Y312103D01*
G01X353447Y315800D02*
X355200D01*
G01X351341Y313694D02*
X353447Y315800D01*
G01X330088Y405044D02*
X333794D01*
G01X330088Y406926D02*
Y405044D01*
G01X330531Y407369D02*
X330088Y406926D01*
G01X330531Y409111D02*
Y407369D01*
G01X337575Y405044D02*
X337592Y405027D01*
G01X333794Y405044D02*
X337575D01*
G01X326083Y412616D02*
Y416366D01*
G01X327365Y419846D02*
Y422661D01*
G01X326083Y418564D02*
X327365Y419846D01*
G01X326083Y416366D02*
Y418564D01*
G01X326588Y406681D02*
Y405044D01*
G01X326083Y407186D02*
X326588Y406681D01*
G01X326083Y409116D02*
Y407186D01*
G01X330531Y418406D02*
Y416439D01*
G01X329925Y419012D02*
X330531Y418406D01*
G01X329925Y429161D02*
Y419012D01*
G01X330531Y416439D02*
Y412611D01*
G01X332458Y443488D02*
X332436Y443510D01*
G01X332458Y439668D02*
Y443488D01*
G01X332485Y439641D02*
X332458Y439668D01*
G01X332485Y435750D02*
Y439641D01*
G01Y435750D02*
Y429161D01*
G01X426689Y152736D02*
X444866D01*
G01X387107Y192318D02*
X426689Y152736D01*
G01X444866D02*
X483129D01*
G01X428494Y159418D02*
X456471D01*
G01X389114Y198798D02*
X428494Y159418D01*
G01X481928Y148279D02*
X434083D01*
G01X421420D02*
X434083D01*
G01X423785Y150586D02*
X457326D01*
G01X427368Y154886D02*
X472891D01*
G01X387646Y194608D02*
X427368Y154886D01*
G01X420529Y146129D02*
X464994D01*
G01X427989Y157094D02*
X465088D01*
G01X388475Y196608D02*
X427989Y157094D01*
G01X448416Y162119D02*
X485062D01*
G01X428622D02*
X448416D01*
G01X389230Y201511D02*
X428622Y162119D01*
G01X407480Y238189D02*
X405512Y236221D01*
G01X407480Y230315D02*
X405512Y228347D01*
G01X403543Y234252D02*
X401575Y232284D01*
G01X415354Y238189D02*
X417322Y236221D01*
G01X403543Y238189D02*
X401575Y236221D01*
G01X407480Y234252D02*
X405512Y232284D01*
G01X403401Y230315D02*
X403543D01*
G01X401727Y228641D02*
X403401Y230315D01*
G01X393580Y236100D02*
X389000D01*
G01X395669Y238189D02*
X393580Y236100D01*
G01X390182Y234252D02*
X389430Y233500D01*
G01X391732Y234252D02*
X390182D01*
G01X415354D02*
X413386Y232284D01*
G01X390881Y232281D02*
X389900Y231300D01*
G01X393698Y232281D02*
X390881D01*
G01X395669Y234252D02*
X393698Y232281D01*
G01X393669Y224378D02*
X395669Y226378D01*
G01X450787Y289371D02*
X448819Y287403D01*
G01X403543Y250000D02*
X401575Y248032D01*
G01X423228Y250000D02*
X421260Y248032D01*
G01X419291Y250000D02*
X417323Y248032D01*
G01X442913Y293308D02*
X440945Y295276D01*
G01X431102Y285434D02*
X433070Y287402D01*
G01X442913Y297245D02*
X440945Y299213D01*
G01X435039Y289371D02*
X433071Y291339D01*
G01X423228Y301182D02*
X421260Y299214D01*
G01X415354Y253937D02*
X413386Y251969D01*
G01X423228Y246063D02*
X421260Y244095D01*
G01X415354Y242125D02*
X413387Y240158D01*
G01X415354Y242126D02*
Y242125D01*
G01X438976Y289371D02*
X437008Y291339D01*
G01X431102Y301182D02*
X429134Y299214D01*
G01X389380Y242126D02*
X391732D01*
G01X389006Y242500D02*
X389380Y242126D01*
G01X419291Y246063D02*
X417323Y244095D01*
G01X446850Y293308D02*
X448818Y295276D01*
G01X415354Y250000D02*
X413386Y248032D01*
G01X435039Y293308D02*
X433071Y295276D01*
G01X411417Y261811D02*
X409449Y259843D01*
G01X403543Y242126D02*
X401575Y240158D01*
G01X407480Y246063D02*
X405512Y244095D01*
G01X435039Y297245D02*
X433071Y299213D01*
G01X431102Y297245D02*
X429134Y295277D01*
G01X442913Y285434D02*
X440945Y287402D01*
G01X427165Y297245D02*
X425197Y299213D01*
G01X394106Y244500D02*
X395669Y246063D01*
G01X394119Y248450D02*
X395669Y250000D01*
G01X388550Y248450D02*
X394119D01*
G01X442913Y289371D02*
X440945Y291339D01*
G01X438976Y297245D02*
X437008Y299213D01*
G01X391732Y246063D02*
X388437D01*
G01X395669Y242126D02*
X393747Y240204D01*
G01X419291Y238189D02*
X417323Y240157D01*
G01X446850Y289371D02*
X448818Y291339D01*
G01X391732Y250000D02*
X389141D01*
G01X438976Y293308D02*
X437008Y295276D01*
G01X423228Y297245D02*
X421260Y295277D01*
G01X423228Y253937D02*
X421260Y251969D01*
G01X419291Y242126D02*
X421259Y240158D01*
G01X407480Y250000D02*
X405512Y248032D01*
G01X427165Y289371D02*
X425197Y291339D01*
G01X435039Y285434D02*
X437007Y287402D01*
G01X427165Y293308D02*
X425197Y295276D01*
G01X403543Y246063D02*
X401575Y244095D01*
G01X415354Y246063D02*
X413386Y244095D01*
G01X431102Y289371D02*
X429134Y287403D01*
G01X407480Y242126D02*
X405512Y240158D01*
G01X419291Y253937D02*
X417323Y251969D01*
G01X431102Y293308D02*
X429134Y291340D01*
G01X419291Y309056D02*
X417323Y311024D01*
G01X431102Y312993D02*
X429134Y314961D01*
G01X442913Y305119D02*
X440945Y307087D01*
G01X438976Y320867D02*
X440944Y322835D01*
G01X448605Y329995D02*
X449312Y329288D01*
G01X448605Y330703D02*
Y329995D01*
G01X449538Y331636D02*
X448605Y330703D01*
G01X448831Y333051D02*
X449538Y332344D01*
G01X448123Y333051D02*
X448831D01*
G01X447190Y332118D02*
X448123Y333051D01*
G01X446482Y332118D02*
X447190D01*
G01X445775Y332825D02*
X446482Y332118D01*
G01X445775Y333533D02*
Y332825D01*
G01X446708Y334466D02*
X445775Y333533D01*
G01X446708Y335174D02*
Y334466D01*
G01X446362Y335520D02*
X446708Y335174D01*
G01X446362Y338238D02*
Y335520D01*
G01X444100Y340500D02*
X446362Y338238D01*
G01X444100Y341000D02*
Y340500D01*
G01X446850Y316930D02*
X444882Y318898D01*
G01X442913Y309056D02*
X440945Y311024D01*
G01X392399Y337659D02*
X392959Y337099D01*
G01X392399Y340563D02*
Y337659D01*
G01X400300Y345150D02*
X395603D01*
G01X392399Y344087D02*
Y340563D01*
G01X393462Y345150D02*
X392399Y344087D01*
G01X395603Y345150D02*
X393462D01*
G01X442913Y324804D02*
Y327204D01*
G01X438976Y301182D02*
X437008Y303150D01*
G01X435039Y316930D02*
X433071Y318898D01*
G01X446850Y305119D02*
X448818Y303151D01*
G01X438976Y324804D02*
Y327204D01*
G01X415354Y312993D02*
X413386Y311025D01*
G01X442913Y301182D02*
X440945Y303150D01*
G01X430464Y347078D02*
Y351272D01*
G01D02*
Y356373D01*
G01X416841Y340334D02*
Y335528D01*
G01X423228Y322228D02*
Y320867D01*
G01X424927Y323927D02*
X423228Y322228D01*
G01X424927Y328073D02*
Y323927D01*
G01X422500Y330500D02*
X424927Y328073D01*
G01X418500Y330500D02*
X422500D01*
G01X416841Y332159D02*
X418500Y330500D01*
G01X416841Y335528D02*
Y332159D01*
G01X437500Y337699D02*
Y340750D01*
G01X437760Y337439D02*
X437500Y337699D01*
G01X437760Y330182D02*
Y337439D01*
G01X437144Y329566D02*
X437760Y330182D01*
G01X437144Y324230D02*
Y329566D01*
G01X435039Y322125D02*
X437144Y324230D01*
G01X435039Y320867D02*
Y322125D01*
G01X440300Y338830D02*
Y337500D01*
G01X438380Y340750D02*
X440300Y338830D01*
G01X437500Y340750D02*
X438380D01*
G01X435039Y301182D02*
X433071Y303150D01*
G01X431102Y322294D02*
Y320867D01*
G01X433489Y324681D02*
X431102Y322294D01*
G01X433489Y331411D02*
Y324681D01*
G01X430409Y334491D02*
X433489Y331411D01*
G01X430409Y335154D02*
Y334491D01*
G01Y337841D02*
Y335154D01*
G01X427700Y340550D02*
X430409Y337841D01*
G01X444200Y332200D02*
X450787Y325613D01*
G01X444200Y337600D02*
Y332200D01*
G01X431102Y331263D02*
Y324804D01*
G01X435039Y312993D02*
X433071Y314961D01*
G01X446850Y312993D02*
X444882Y314961D01*
G01X427165Y312993D02*
X425197Y314961D01*
G01X423228Y324804D02*
X421260Y326772D01*
G01X431102Y305119D02*
X429134Y303151D01*
G01X407292Y343738D02*
X407304Y343726D01*
G01X407292Y345788D02*
Y343738D01*
G01X405921Y347159D02*
X407292Y345788D01*
G01Y343714D02*
X407304Y343726D01*
G01X407292Y341815D02*
Y343714D01*
G01X408773Y340334D02*
X407292Y341815D01*
G01X412400Y340334D02*
X408773D01*
G01X427165Y322238D02*
Y320867D01*
G01X428796Y323869D02*
X427165Y322238D01*
G01X428796Y331985D02*
Y323869D01*
G01X425500Y335281D02*
X428796Y331985D01*
G01X425500Y339887D02*
Y335281D01*
G01X424117Y341270D02*
X425500Y339887D01*
G01X424117Y343810D02*
Y341270D01*
G01X421375Y346552D02*
X424117Y343810D01*
G01X415354Y320867D02*
X417322Y322835D01*
G01X423228Y309056D02*
X421260Y307088D01*
G01X423228Y312993D02*
X421260Y314961D01*
G01X431102Y316930D02*
X429134Y318898D01*
G01X445696Y324804D02*
X446850D01*
G01X444550Y325950D02*
X445696Y324804D01*
G01X444550Y328550D02*
Y325950D01*
G01X442800Y330300D02*
X444550Y328550D01*
G01X427165Y301182D02*
X425197Y303150D01*
G01X415354Y316930D02*
X413386Y314962D01*
G01X427165Y316930D02*
X425197Y318898D01*
G01X450787Y309056D02*
X448819Y307088D01*
G01X438976Y305119D02*
X437008Y307087D01*
G01X446850Y322470D02*
Y320867D01*
G01X448700Y324320D02*
X446850Y322470D01*
G01X448700Y325600D02*
Y324320D01*
G01X446900Y327400D02*
X448700Y325600D01*
G01X446200Y327400D02*
X446900D01*
G01X446850Y309056D02*
X448818Y311024D01*
G01X419291Y320867D02*
X421259Y322835D01*
G01X431102Y309056D02*
X429134Y311024D01*
G01X435039Y336422D02*
Y324804D01*
G01X435350Y336733D02*
X435039Y336422D01*
G01X435350Y338350D02*
Y336733D01*
G01X432200Y341500D02*
X435350Y338350D01*
G01X442913Y320867D02*
X444881Y322835D01*
G01X423228Y305119D02*
X421260Y303151D01*
G01X438976Y309056D02*
X437008Y311024D01*
G01X423500Y339058D02*
X421357Y341201D01*
G01X423500Y333228D02*
Y339058D01*
G01X427165Y329563D02*
X423500Y333228D01*
G01X427165Y324804D02*
Y329563D01*
G01X423228Y316930D02*
X421260Y318898D01*
G01X451400Y340750D02*
X447300D01*
G01X438976Y312993D02*
X437008Y314961D01*
G01X438976Y316930D02*
X437008Y318898D01*
G01X435773Y432820D02*
X425197Y422244D01*
G01X439578Y430129D02*
X422244Y412795D01*
G01X445433Y427520D02*
X425197Y407284D01*
G01X422244Y451506D02*
Y457677D01*
G01X430330Y443420D02*
X422244Y451506D01*
G01X485500Y443420D02*
X430330D01*
G01X424461Y440500D02*
X488420D01*
G01X422244Y442717D02*
X424461Y440500D01*
G01X429758Y435270D02*
X488350D01*
G01X422244Y427756D02*
X429758Y435270D01*
G01X426112Y438120D02*
X485500D01*
G01X425197Y437205D02*
X426112Y438120D01*
G01X431762Y445600D02*
X488620D01*
G01X425197Y452165D02*
X431762Y445600D01*
G01X485500Y432820D02*
X435773D01*
G01X488191Y430129D02*
X439578D01*
G01X485500Y427520D02*
X445433D01*
G01X491893Y37242D02*
X494489Y34646D01*
G01X491893Y83916D02*
Y37242D01*
G01X463610Y37178D02*
Y83884D01*
G01X466142Y34646D02*
X463610Y37178D01*
G01X484806Y32518D02*
Y84097D01*
G01X487402Y29922D02*
X484806Y32518D01*
G01X498979D02*
X501575Y29922D01*
G01X498979Y82914D02*
Y32518D01*
G01X454437Y29028D02*
Y81563D01*
G01X459055Y24410D02*
X454437Y29028D01*
G01X470739Y32412D02*
Y84520D01*
G01X473229Y29922D02*
X470739Y32412D01*
G01X477719Y37242D02*
Y84098D01*
G01X480315Y34646D02*
X477719Y37242D01*
G01X468633Y29006D02*
X473229Y24410D01*
G01X468633Y83797D02*
Y29006D01*
G01X489893Y33730D02*
Y81839D01*
G01X494489Y29134D02*
X489893Y33730D01*
G01X506067Y37241D02*
X508662Y34646D01*
G01X506067Y81912D02*
Y37241D01*
G01X475719Y33730D02*
Y83269D01*
G01X480315Y29134D02*
X475719Y33730D01*
G01X482806Y29006D02*
Y81840D01*
G01X487402Y24410D02*
X482806Y29006D01*
G01X456460Y32517D02*
X459055Y29922D01*
G01X456460Y82440D02*
Y32517D01*
G01X504066Y33730D02*
X508662Y29134D01*
G01X504066Y80870D02*
Y33730D01*
G01X496979Y29006D02*
Y81873D01*
G01X501575Y24410D02*
X496979Y29006D01*
G01X461610Y33666D02*
Y82537D01*
G01X466142Y29134D02*
X461610Y33666D01*
G01X470537Y105272D02*
X491893Y83916D01*
G01X467756Y108053D02*
X470537Y105272D01*
G01X487008Y137123D02*
X548585Y75546D01*
G01X476590Y132555D02*
X532412Y76733D01*
G01X456819Y88501D02*
X456818Y88500D01*
G01X458993Y88501D02*
X456819D01*
G01X463610Y83884D02*
X458993Y88501D01*
G01X484806Y84097D02*
X464850Y104053D01*
G01X490923Y130166D02*
X546585Y74504D01*
G01X475761Y130555D02*
X527000Y79316D01*
G01X469822Y112071D02*
X471096Y110797D01*
G01D02*
X498979Y82914D01*
G01X476974Y135000D02*
X534413Y77561D01*
G01X454437Y81563D02*
X453500Y82500D01*
G01X518239Y78649D02*
X482779Y114109D01*
G01X470739Y84520D02*
X462559Y92700D01*
G01X477719Y84098D02*
X461764Y100053D01*
G01X461730Y90700D02*
X468633Y83797D01*
G01X472737Y118071D02*
X511152Y79656D01*
G01X489893Y81839D02*
X465679Y106053D01*
G01X471908Y116071D02*
X506067Y81912D01*
G01X477259Y137544D02*
X539499Y75304D01*
G01X475719Y83269D02*
X460935Y98053D01*
G01X482806Y81840D02*
X462593Y102053D01*
G01X454400Y84500D02*
X456460Y82440D01*
G01X473566Y120071D02*
X513153Y80484D01*
G01X479435Y105501D02*
X504066Y80870D01*
G01X470865Y114071D02*
X479435Y105501D01*
G01X520248Y79682D02*
X479830Y120100D01*
G01X525400Y77874D02*
X477011Y126263D01*
G01X494472Y123575D02*
X541499Y76548D01*
G01X496979Y81873D02*
X468781Y110071D01*
G01X461610Y82537D02*
X457647Y86500D01*
G01X483129Y152736D02*
X562759Y73106D01*
G01X480287Y143844D02*
X487008Y137123D01*
G01X490923Y130166D02*
X479395Y141694D01*
G01X484934Y159418D02*
X574932Y69420D01*
G01X456471Y159418D02*
X484934D01*
G01X555672Y74535D02*
X481928Y148279D01*
G01X482450Y150586D02*
X560759Y72277D01*
G01X457326Y150586D02*
X482450D01*
G01X483808Y154886D02*
X472891D01*
G01X567845Y70849D02*
X483808Y154886D01*
G01X482779Y114109D02*
X474743Y122145D01*
G01X481249Y146129D02*
X553672Y73706D01*
G01X464994Y146129D02*
X481249D01*
G01X484429Y157094D02*
X569845Y71678D01*
G01X465088Y157094D02*
X484429D01*
G01X479830Y120100D02*
X473375Y126555D01*
G01X474719Y128555D02*
X477011Y126263D01*
G01X494472Y123575D02*
X478503Y139544D01*
G01X485062Y162119D02*
X576933Y70248D01*
G01X501969Y202756D02*
X503937Y200788D01*
G01X498032Y202756D02*
X500000Y200788D01*
G01X450787Y297245D02*
X452755Y295277D01*
G01X486221Y293308D02*
X488189Y295276D01*
G01X474410Y285434D02*
X472442Y287402D01*
G01X458662Y293308D02*
X456694Y295276D01*
G01X450787Y285434D02*
X452755Y287402D01*
G01X458662Y297245D02*
X460630Y299213D01*
G01X466536Y301182D02*
X468504Y299214D01*
G01X482284Y285434D02*
X484252Y287402D01*
G01X454725Y289371D02*
X456693Y291339D01*
G01X466536Y285434D02*
X464568Y287402D01*
G01X478347Y293308D02*
X480315Y295276D01*
G01X458662Y289371D02*
X460630Y291339D01*
G01X482284Y293308D02*
X484252Y291340D01*
G01X450787Y293308D02*
X452755Y291340D01*
G01X482284Y289371D02*
X480316Y287403D01*
G01X478347Y289371D02*
X480315Y291339D01*
G01X474410Y289371D02*
X476378Y291339D01*
G01X482284Y297245D02*
X484252Y295277D01*
G01X470473Y289371D02*
X472441Y291339D01*
G01X486221Y309056D02*
X488189Y311024D01*
G01X483500Y338369D02*
Y336000D01*
G01X484131Y339000D02*
X483500Y338369D01*
G01X484131Y347769D02*
Y339000D01*
G01X481100Y350800D02*
X484131Y347769D01*
G01X477650Y350800D02*
X481100D01*
G01X483500Y334500D02*
Y336000D01*
G01X481515Y332515D02*
X483500Y334500D01*
G01X472789Y332515D02*
X481515D01*
G01X468086Y327812D02*
X472789Y332515D01*
G01X468086Y322417D02*
Y327812D01*
G01X466536Y320867D02*
X468086Y322417D01*
G01X473847Y354603D02*
Y358638D01*
G01X477650Y350800D02*
X473847Y354603D01*
G01X490158Y309056D02*
X492126Y311024D01*
G01X513267Y336102D02*
X501969Y324804D01*
G01X509843D02*
X511255D01*
G01X519424Y330448D02*
X509843Y320867D01*
G01X470473Y312993D02*
X472441Y314961D01*
G01X450787Y322436D02*
Y320867D01*
G01X452624Y324273D02*
X450787Y322436D01*
G01X452624Y329258D02*
Y324273D01*
G01X451661Y330221D02*
X452624Y329258D01*
G01X450953Y330221D02*
X451661D01*
G01X450020Y329288D02*
X450953Y330221D01*
G01X449312Y329288D02*
X450020D01*
G01X449538Y332344D02*
Y331636D01*
G01X454725Y309056D02*
X456693Y311024D01*
G01X488444Y349114D02*
Y338409D01*
G01X482634Y354924D02*
X488444Y349114D01*
G01X482427Y354924D02*
X482634D01*
G01X474410Y322234D02*
Y320867D01*
G01X476796Y324620D02*
X474410Y322234D01*
G01X476796Y326197D02*
Y324620D01*
G01X479259Y328660D02*
X476796Y326197D01*
G01X484041Y328660D02*
X479259D01*
G01X488444Y333063D02*
X484041Y328660D01*
G01X488444Y338409D02*
Y333063D01*
G01X512000Y319087D02*
X509843Y316930D01*
G01X501969Y312993D02*
X500001Y314961D01*
G01X462599Y305119D02*
X464567Y303151D01*
G01X501969Y305119D02*
X503937Y307087D01*
G01X486221Y305119D02*
X488189Y307087D01*
G01X470473Y324804D02*
Y327204D01*
G01X491474Y346364D02*
Y342209D01*
G01X490468Y347370D02*
X491474Y346364D01*
G01X490468Y349332D02*
Y347370D01*
G01X490444Y349356D02*
X490468Y349332D01*
G01X490444Y349943D02*
Y349356D01*
G01X486627Y353760D02*
X490444Y349943D01*
G01X486627Y354924D02*
Y353760D01*
G01X490476Y332996D02*
X482284Y324804D01*
G01X490476Y337400D02*
Y332996D01*
G01X490594Y337518D02*
X490476Y337400D01*
G01X490594Y339194D02*
Y337518D01*
G01X491474Y340074D02*
X490594Y339194D01*
G01X491474Y342209D02*
Y340074D01*
G01X494095Y316930D02*
X496063Y318898D01*
G01X509101Y327999D02*
X505906Y324804D01*
G01X509912Y327999D02*
X509101D01*
G01X523602Y341689D02*
X509912Y327999D01*
G01X458662Y301182D02*
X460630Y303150D01*
G01X486221Y301182D02*
X488189Y303150D01*
G01X472463Y324439D02*
Y329837D01*
G01X470473Y322449D02*
X472463Y324439D01*
G01X470473Y320867D02*
Y322449D01*
G01X478298Y362352D02*
Y358304D01*
G01X458662Y329332D02*
Y324804D01*
G01X464300Y334970D02*
X458662Y329332D01*
G01X464300Y337500D02*
Y334970D01*
G01X461049Y340751D02*
X464300Y337500D01*
G01X460327Y340751D02*
X461049D01*
G01X494095Y309056D02*
X496063Y311024D01*
G01X450787Y325613D02*
Y324804D01*
G01X462599Y309056D02*
X464567Y307088D01*
G01X450787Y305119D02*
X452755Y307087D01*
G01X458662Y305119D02*
X460630Y307087D01*
G01X501969Y316930D02*
X503937Y318898D01*
G01X494095Y312993D02*
X496063Y314961D01*
G01X454725Y312993D02*
X456693Y314961D01*
G01X469719Y343327D02*
X472296Y340750D01*
G01X469719Y346012D02*
Y343327D01*
G01X470544Y346837D02*
X469719Y346012D01*
G01X470544Y350414D02*
Y346837D01*
G01X469996Y350962D02*
X470544Y350414D01*
G01X472724Y340322D02*
X472296Y340750D01*
G01X472724Y335567D02*
Y340322D01*
G01X466536Y327752D02*
Y324804D01*
G01X472724Y333940D02*
X466536Y327752D01*
G01X472724Y335567D02*
Y333940D01*
G01X462599Y322611D02*
Y320867D01*
G01X464536Y324548D02*
X462599Y322611D01*
G01X464536Y327224D02*
Y324548D01*
G01X469755Y332443D02*
X464536Y327224D01*
G01X469755Y336126D02*
Y332443D01*
G01X470301Y336672D02*
X469755Y336126D01*
G01X470301Y338328D02*
Y336672D01*
G01X466470Y342159D02*
X470301Y338328D01*
G01X466470Y350311D02*
Y342159D01*
G01X465300Y351481D02*
X466470Y350311D01*
G01X505906Y309056D02*
X507874Y311024D01*
G01X462599Y316930D02*
X464567Y318898D01*
G01X470473Y309056D02*
X468505Y307088D01*
G01X454725Y305119D02*
X456693Y307087D01*
G01X493700Y347200D02*
X493200Y347700D01*
G01X493700Y346014D02*
Y347200D01*
G01X494077Y345637D02*
X493700Y346014D01*
G01X494077Y339377D02*
Y345637D01*
G01X492594Y337894D02*
X494077Y339377D01*
G01X492594Y336617D02*
Y337894D01*
G01X492367Y336390D02*
X492594Y336617D01*
G01X492367Y333250D02*
Y336390D01*
G01X484671Y325554D02*
X492367Y333250D01*
G01X484671Y324171D02*
Y325554D01*
G01X482284Y321784D02*
X484671Y324171D01*
G01X482284Y320867D02*
Y321784D01*
G01X450787Y301182D02*
X452755Y303150D01*
G01X462599Y312993D02*
X464567Y311025D01*
G01X511787Y311000D02*
X509843Y309056D01*
G01X454725Y322403D02*
Y320867D01*
G01X456910Y324588D02*
X454725Y322403D01*
G01X456910Y334910D02*
Y324588D01*
G01X457500Y335500D02*
X456910Y334910D01*
G01X459800Y335500D02*
X457500D01*
G01X460300Y335000D02*
X459800Y335500D01*
G01X460300Y333500D02*
Y335000D01*
G01X482284Y305119D02*
X484252Y307087D01*
G01X482284Y301182D02*
X484252Y303150D01*
G01X488189Y318898D02*
X486221Y316930D01*
G01X488189Y322835D02*
Y318898D01*
G01X498032Y309056D02*
X500000Y307088D01*
G01X470473Y305119D02*
X472441Y307087D01*
G01X454725Y316930D02*
X456693Y318898D01*
G01X466536Y309056D02*
X468504Y311024D01*
G01X510683Y312993D02*
X509843D01*
G01X512559Y314869D02*
X510683Y312993D01*
G01X510969Y326999D02*
X518469Y334499D01*
G01X510678Y326999D02*
X510969D01*
G01X510133Y326454D02*
X510678Y326999D01*
G01X509159Y326454D02*
X510133D01*
G01X508193Y325488D02*
X509159Y326454D01*
G01X508193Y324387D02*
Y325488D01*
G01X505906Y322100D02*
X508193Y324387D01*
G01X505906Y320867D02*
Y322100D01*
G01X501969Y322089D02*
Y320867D01*
G01X504256Y324376D02*
X501969Y322089D01*
G01X504256Y325488D02*
Y324376D01*
G01X505222Y326454D02*
X504256Y325488D01*
G01X505236Y326454D02*
X505222D01*
G01X517097Y338315D02*
X505236Y326454D01*
G01X490158Y305119D02*
X492126Y307087D01*
G01X474410Y309056D02*
X476378Y311024D01*
G01X458662Y309056D02*
X460630Y311024D01*
G01X466536Y305119D02*
X468504Y303151D01*
G01X480302Y352800D02*
X478298Y354804D01*
G01X481929Y352800D02*
X480302D01*
G01X486281Y348448D02*
X481929Y352800D01*
G01X486281Y346317D02*
Y348448D01*
G01Y333622D02*
Y346317D01*
G01X482902Y330243D02*
X486281Y333622D01*
G01X479427Y330243D02*
X482902D01*
G01X474410Y325226D02*
X479427Y330243D01*
G01X474410Y324804D02*
Y325226D01*
G01X465049Y340751D02*
X468300Y337500D01*
G01X464327Y340751D02*
X465049D01*
G01X458662Y321654D02*
Y320867D01*
G01X460746Y323738D02*
X458662Y321654D01*
G01X460746Y328217D02*
Y323738D01*
G01X462379Y329850D02*
X460746Y328217D01*
G01X463087Y329850D02*
X462379D01*
G01X463826Y329111D02*
X463087Y329850D01*
G01X464534Y329111D02*
X463826D01*
G01X465241Y329818D02*
X464534Y329111D01*
G01X465241Y330526D02*
Y329818D01*
G01X463953Y331813D02*
X465241Y330526D01*
G01X463953Y332519D02*
Y331813D01*
G01X464663Y333229D02*
X463953Y332519D01*
G01X465369Y333229D02*
X464663D01*
G01X466656Y331941D02*
X465369Y333229D01*
G01X467364Y331941D02*
X466656D01*
G01X468071Y332648D02*
X467364Y331941D01*
G01X468071Y333356D02*
Y332648D01*
G01X466840Y334587D02*
X468071Y333356D01*
G01X466840Y336040D02*
Y334587D01*
G01X468300Y337500D02*
X466840Y336040D01*
G01X476500Y340750D02*
X480700D01*
G01X470473Y316930D02*
X472441Y318898D01*
G01X480700Y338283D02*
Y340750D01*
G01X479640Y337223D02*
X480700Y338283D01*
G01X479640Y334674D02*
Y337223D01*
G01X462599Y324804D02*
Y327204D01*
G01X454700Y324829D02*
X454725Y324804D01*
G01X454700Y338543D02*
Y324829D01*
G01X455900Y339743D02*
X454700Y338543D01*
G01X455900Y341100D02*
Y339743D01*
G01X453600Y341100D02*
X455900D01*
G01X453250Y340750D02*
X453600Y341100D01*
G01X451400Y340750D02*
X453250D01*
G01X501969Y309056D02*
X503937Y311024D01*
G01X478250Y366800D02*
Y362400D01*
G01D02*
X478298Y362352D01*
G01X475523Y369527D02*
X478250Y366800D01*
G01X489600Y367209D02*
X482705Y374104D01*
G01X488420Y440500D02*
X490800Y438120D01*
G01X488350Y435270D02*
X490800Y432820D01*
G01X488620Y445600D02*
X490800Y443420D01*
G01Y427520D02*
X488191Y430129D01*
G01X562759Y37242D02*
X565355Y34646D01*
G01X562759Y73106D02*
Y37242D01*
G01X548585D02*
X551181Y34646D01*
G01X548585Y75546D02*
Y37242D01*
G01X532412Y33730D02*
X537008Y29134D01*
G01X532412Y76733D02*
Y33730D01*
G01X546585D02*
X551181Y29134D01*
G01X546585Y74504D02*
Y33730D01*
G01X555672Y32518D02*
Y74535D01*
G01X558268Y29922D02*
X555672Y32518D01*
G01X560759Y33730D02*
X565355Y29134D01*
G01X560759Y72277D02*
Y33730D01*
G01X527400Y32444D02*
X529922Y29922D01*
G01X527400Y78703D02*
Y32444D01*
G01X567845Y29006D02*
Y70849D01*
G01X572441Y24410D02*
X567845Y29006D01*
G01X534413Y37241D02*
X537008Y34646D01*
G01X534413Y77561D02*
Y37241D01*
G01X518239Y33730D02*
Y78649D01*
G01X522835Y29134D02*
X518239Y33730D01*
G01X511152Y29006D02*
X515748Y24410D01*
G01X511152Y79656D02*
Y29006D01*
G01X539499D02*
X544095Y24410D01*
G01X539499Y75304D02*
Y29006D01*
G01X553672D02*
X558268Y24410D01*
G01X553672Y73706D02*
Y29006D01*
G01X569845Y32518D02*
X572441Y29922D01*
G01X569845Y71678D02*
Y32518D01*
G01X513153Y32517D02*
X515748Y29922D01*
G01X513153Y80484D02*
Y32517D01*
G01X520248Y37233D02*
Y79682D01*
G01X522835Y34646D02*
X520248Y37233D01*
G01X525400Y28932D02*
Y77874D01*
G01X529922Y24410D02*
X525400Y28932D01*
G01X541499Y32518D02*
X544095Y29922D01*
G01X541499Y76548D02*
Y32518D01*
G01X527000Y79103D02*
X527400Y78703D01*
G01X527000Y79316D02*
Y79103D01*
G01X513267Y337436D02*
Y336102D01*
G01X515254Y339423D02*
X513267Y337436D01*
G01X515254Y340866D02*
Y339423D01*
G01X518020Y343632D02*
X515254Y340866D01*
G01X518000Y350829D02*
Y351400D01*
G01X516288Y349117D02*
X518000Y350829D01*
G01X516288Y347563D02*
Y349117D01*
G01X518020Y345831D02*
X516288Y347563D01*
G01X518020Y343632D02*
Y345831D01*
G01X552200Y340543D02*
Y339300D01*
G01X548483Y344260D02*
X552200Y340543D01*
G01X533333Y344260D02*
X548483D01*
G01X531850Y342777D02*
X533333Y344260D01*
G01X531850Y341632D02*
Y342777D01*
G01X528806Y338588D02*
X531850Y341632D01*
G01X526160Y338588D02*
X528806D01*
G01X522352Y334780D02*
X526160Y338588D01*
G01X521231Y334780D02*
X522352D01*
G01X511255Y324804D02*
X521231Y334780D01*
G01X519629Y330448D02*
X519424D01*
G01X521797D02*
X519629D01*
G01X527028Y335679D02*
X521797Y330448D01*
G01X527865Y335679D02*
X527028D01*
G01X512000Y321421D02*
Y319087D01*
G01X517671Y327092D02*
X512000Y321421D01*
G01X519263Y327092D02*
X517671D01*
G01X521484Y329313D02*
X519263Y327092D01*
G01X523032Y329313D02*
X521484D01*
G01X525398Y331679D02*
X523032Y329313D01*
G01X527865Y331679D02*
X525398D01*
G01X523602Y345779D02*
Y341689D01*
G01X525388Y347565D02*
X528894D01*
G01X523602Y345779D02*
X525388Y347565D01*
G01X535336Y330858D02*
Y331772D01*
G01X533673Y329195D02*
X535336Y330858D01*
G01X524681Y329195D02*
X533673D01*
G01X516353Y320867D02*
X524681Y329195D01*
G01X513780Y320867D02*
X516353D01*
G01X535883Y331772D02*
X538476Y334365D01*
G01X535336Y331772D02*
X535883D01*
G01X516446Y309056D02*
X513780D01*
G01X519600Y312210D02*
X516446Y309056D01*
G01X519600Y316061D02*
Y312210D01*
G01X526734Y323195D02*
X519600Y316061D01*
G01X536450Y323195D02*
X526734D01*
G01X540027Y326772D02*
X536450Y323195D01*
G01X542622Y326772D02*
X540027D01*
G01X544826Y328976D02*
X542622Y326772D01*
G01X546876Y328976D02*
X544826D01*
G01X547594Y329694D02*
X546876Y328976D01*
G01X550394Y329694D02*
X547594D01*
G01X551394Y330694D02*
X550394Y329694D01*
G01X551394Y331738D02*
Y330694D01*
G01X553013Y331738D02*
X551394D01*
G01X554685Y333410D02*
X553013Y331738D01*
G01X516834Y311000D02*
X511787D01*
G01X518456Y312622D02*
X516834Y311000D01*
G01X518456Y317499D02*
Y312622D01*
G01X521116Y320159D02*
X518456Y317499D01*
G01X521116Y320429D02*
Y320159D01*
G01X525882Y325195D02*
X521116Y320429D01*
G01X535542Y325195D02*
X525882D01*
G01X538698Y328351D02*
X535542Y325195D01*
G01X538777Y328351D02*
X538698D01*
G01X539330Y328904D02*
X538777Y328351D01*
G01X541694Y328904D02*
X539330D01*
G01X541776Y328986D02*
X541694Y328904D01*
G01X542007Y328986D02*
X541776D01*
G01X543997Y330976D02*
X542007Y328986D01*
G01X546047Y330976D02*
X543997D01*
G01X546765Y331694D02*
X546047Y330976D01*
G01X547271Y331694D02*
X546765D01*
G01X547315Y331738D02*
X547271Y331694D01*
G01X546565Y332488D02*
X547315Y331738D01*
G01X546175Y332488D02*
X546565D01*
G01X544565Y334098D02*
X546175Y332488D01*
G01X544565Y341428D02*
Y334098D01*
G01X543646Y342347D02*
X544565Y341428D01*
G01X514411Y314869D02*
X512559D01*
G01X520116Y320574D02*
X514411Y314869D01*
G01X520116Y322240D02*
Y320574D01*
G01X525071Y327195D02*
X520116Y322240D01*
G01X534713Y327195D02*
X525071D01*
G01X538436Y330918D02*
X534713Y327195D01*
G01X538450Y330904D02*
X538436Y330918D01*
G01X540865Y330904D02*
X538450D01*
G01X541714Y331753D02*
X540865Y330904D01*
G01X527765Y340588D02*
X528902Y341725D01*
G01X525331Y340588D02*
X527765D01*
G01X519242Y334499D02*
X525331Y340588D01*
G01X518469Y334499D02*
X519242D01*
G01X528902Y343402D02*
Y341725D01*
G01X530750Y345250D02*
X528902Y343402D01*
G01X530750Y345421D02*
Y345250D01*
G01X532894Y347565D02*
X530750Y345421D01*
G01X520506Y349906D02*
X522000Y351400D01*
G01X520506Y341724D02*
Y349906D01*
G01X517097Y338315D02*
X520506Y341724D01*
G01X562460Y462070D02*
Y457580D01*
G01X627603Y43523D02*
Y54344D01*
G01X574932Y33730D02*
X579528Y29134D01*
G01X574932Y69420D02*
Y33730D01*
G01X628839Y18000D02*
X627500Y19339D01*
G01X633000Y18000D02*
X628839D01*
G01X634617D02*
X638941Y22324D01*
G01X633000Y18000D02*
X634617D01*
G01X633423Y31609D02*
X635791Y29241D01*
G01X632416Y31609D02*
X633423D01*
G01X576932Y37242D02*
X579528Y34646D01*
G01X576932Y69899D02*
Y37242D01*
G01X628901Y55642D02*
X632343D01*
G01X627603Y54344D02*
X628901Y55642D01*
G01X637700D02*
X632343D01*
G01X635000Y64500D02*
X627500D01*
G01X642000Y57500D02*
X635000Y64500D01*
G01X633385Y61500D02*
X629500D01*
G01X636943Y57942D02*
X633385Y61500D01*
G01X576933Y69900D02*
X576932Y69899D01*
G01X576933Y70248D02*
Y69900D01*
G01X628446Y160854D02*
X645150D01*
G01X626800Y162500D02*
X628446Y160854D01*
G01X625750Y162500D02*
X626800D01*
G01X621750Y168536D02*
Y166500D01*
G01X620778Y169508D02*
X621750Y168536D01*
G01X619538Y169508D02*
X620778D01*
G01X616500Y172546D02*
X619538Y169508D01*
G01X616500Y175874D02*
Y172546D01*
G01X622250Y166000D02*
Y162500D01*
G01X621750Y166500D02*
X622250Y166000D01*
G01X626250Y165879D02*
Y166500D01*
G01X629275Y162854D02*
X626250Y165879D01*
G01X642657Y162854D02*
X629275D01*
G01X627464Y169348D02*
Y173443D01*
G01X626250Y168134D02*
X627464Y169348D01*
G01X626250Y166500D02*
Y168134D01*
G01X620125Y179499D02*
X616500Y175874D01*
G01X623566Y179499D02*
X620125D01*
G01X602273Y285503D02*
Y288661D01*
G01X600787Y284017D02*
X602273Y285503D01*
G01X600787Y280017D02*
Y284017D01*
G01X602273Y288877D02*
Y288661D01*
G01X600450Y290700D02*
X602273Y288877D01*
G01X600450Y294600D02*
Y290700D01*
G01X601204Y295354D02*
X600450Y294600D01*
G01X605020Y295354D02*
X601204D01*
G01X614000Y297440D02*
Y302550D01*
G01X608273Y291713D02*
X614000Y297440D01*
G01X608273Y288661D02*
Y291713D01*
G01Y286569D02*
Y288661D01*
G01X608711Y286131D02*
X608273Y286569D01*
G01X608711Y283655D02*
Y286131D01*
G01Y278476D02*
Y280155D01*
G01X606024Y275789D02*
X608711Y278476D01*
G01X594507Y275789D02*
X606024D01*
G01X591648Y278648D02*
X594507Y275789D01*
G01X591648Y314948D02*
Y278648D01*
G01X613211Y277606D02*
Y280155D01*
G01X609294Y273689D02*
X613211Y277606D01*
G01X593248Y273689D02*
X609294D01*
G01X589648Y277289D02*
X593248Y273689D01*
G01X589648Y316948D02*
Y277289D01*
G01X630888Y281785D02*
Y284129D01*
G01X629250Y280147D02*
X630888Y281785D01*
G01X629250Y278745D02*
Y280147D01*
G01Y287984D02*
Y288745D01*
G01X630888Y286346D02*
X629250Y287984D01*
G01X630888Y284129D02*
Y286346D01*
G01X624646Y297319D02*
X621320D01*
G01X625224Y296741D02*
X624646Y297319D01*
G01X626738Y296741D02*
X625224D01*
G01X629250Y294229D02*
X626738Y296741D01*
G01X629250Y288745D02*
Y294229D01*
G01X614273Y294419D02*
Y288661D01*
G01X616500Y296646D02*
X614273Y294419D01*
G01X616500Y302200D02*
Y296646D01*
G01X614273Y286601D02*
Y288661D01*
G01X613211Y285539D02*
X614273Y286601D01*
G01X613211Y283655D02*
Y285539D01*
G01X625250Y278745D02*
Y284066D01*
G01D02*
Y288745D01*
G01X626550Y290045D02*
X625250Y288745D01*
G01X626550Y294100D02*
Y290045D01*
G01X625296Y295354D02*
X626550Y294100D01*
G01X621320Y295354D02*
X625296D01*
G01X617600Y348900D02*
X616800Y348100D01*
G01X622300Y348900D02*
X617600D01*
G01X614500Y345800D02*
X616800Y348100D01*
G01X614500Y343329D02*
Y345800D01*
G01X610839Y339668D02*
X614500Y343329D01*
G01X605020Y339668D02*
X610839D01*
G01X608607Y326656D02*
X604037D01*
G01X616133Y341633D02*
X621320D01*
G01X613745Y339245D02*
X616133Y341633D01*
G01X613745Y329345D02*
Y339245D01*
G01X611056Y326656D02*
X613745Y329345D01*
G01X608607Y326656D02*
X611056D01*
G01X625259Y301259D02*
X621320D01*
G01X626000Y302000D02*
X625259Y301259D01*
G01X626000Y305000D02*
Y302000D01*
G01X625000Y306000D02*
X626000Y305000D01*
G01X617450Y306000D02*
X625000D01*
G01X614000Y302550D02*
X617450Y306000D01*
G01X597200Y342350D02*
X597250Y342400D01*
G01X597200Y337950D02*
Y342350D01*
G01X597250Y337900D02*
X597200Y337950D01*
G01X601772Y335728D02*
X605020D01*
G01X599600Y337900D02*
X601772Y335728D01*
G01X597250Y337900D02*
X599600D01*
G01X597250Y343450D02*
Y342400D01*
G01X593750Y346950D02*
X597250Y343450D01*
G01X613074Y321774D02*
X612907D01*
G01X615800Y324500D02*
X613074Y321774D01*
G01X615800Y338247D02*
Y324500D01*
G01X617221Y339668D02*
X615800Y338247D01*
G01X621320Y339668D02*
X617221D01*
G01X607000Y321774D02*
X612907D01*
G01X606318Y322456D02*
X607000Y321774D01*
G01X604037Y322456D02*
X606318D01*
G01X599156D02*
X597450Y320750D01*
G01X600537Y322456D02*
X599156D01*
G01X597450Y320750D02*
X591648Y314948D01*
G01X599356Y326656D02*
X597450Y324750D01*
G01X600537Y326656D02*
X599356D01*
G01X597450Y324750D02*
X589648Y316948D01*
G01X617524Y303224D02*
X616500Y302200D01*
G01X621320Y303224D02*
X617524D01*
G01X625250Y323992D02*
X624108Y322850D01*
G01X625250Y327654D02*
Y323992D01*
G01X624237Y333763D02*
X621320D01*
G01X625250Y332750D02*
X624237Y333763D01*
G01X625250Y327654D02*
Y332750D01*
G01X624108Y322850D02*
X618900D01*
G01X600250Y333763D02*
X605020D01*
G01X599663Y334350D02*
X600250Y333763D01*
G01X597250Y334350D02*
X599663D01*
G01X597250Y330756D02*
X596631Y330137D01*
G01X597250Y334350D02*
Y330756D01*
G01X592400Y330500D02*
X590350D01*
G01X592763Y330137D02*
X592400Y330500D01*
G01X596631Y330137D02*
X592763D01*
G01X612410Y348239D02*
X610982D01*
G01X615800Y351629D02*
X612410Y348239D01*
G01X615800Y353400D02*
Y351629D01*
G01X619800Y353400D02*
X615800D01*
G01X601743Y341633D02*
X605020D01*
G01X600980Y342396D02*
X601743Y341633D01*
G01X600980Y344403D02*
Y342396D01*
G01X602527Y345950D02*
X600980Y344403D01*
G01X603321Y345950D02*
X602527D01*
G01X603654Y346283D02*
X603321Y345950D01*
G01X603899Y346283D02*
X603654D01*
G01X605855Y348239D02*
X603899Y346283D01*
G01X610982Y348239D02*
X605855D01*
G01X625272Y335728D02*
X621320D01*
G01X626048Y334952D02*
X625272Y335728D01*
G01X628364Y334952D02*
X626048D01*
G01X629250Y334066D02*
X628364Y334952D01*
G01X629250Y332319D02*
Y334066D01*
G01Y327654D02*
Y332319D01*
G01Y326293D02*
Y327654D01*
G01X631800Y323743D02*
X629250Y326293D01*
G01X631800Y322750D02*
Y323743D01*
G01X609259Y301259D02*
X605020D01*
G01X613100Y305100D02*
X609259Y301259D01*
G01X613100Y307100D02*
Y305100D01*
G01X615900Y309900D02*
X613100Y307100D01*
G01X616491Y310491D02*
X622300D01*
G01X615900Y309900D02*
X616491Y310491D01*
G01X602298Y310168D02*
X608157D01*
G01X600594Y308464D02*
X602298Y310168D01*
G01X600594Y303743D02*
Y308464D01*
G01X601113Y303224D02*
X600594Y303743D01*
G01X605020Y303224D02*
X601113D01*
G01X610477Y310168D02*
X608157D01*
G01X615300Y314991D02*
X610477Y310168D01*
G01X619800Y314991D02*
X615300D01*
G01X622109Y385304D02*
X627078D01*
G01X619143D02*
X622109D01*
G01X618282Y386165D02*
X619143Y385304D01*
G01X614220Y386165D02*
X618282D01*
G01X622109Y364424D02*
X627078D01*
G01X621223D02*
X622109D01*
G01X620584Y363785D02*
X621223Y364424D01*
G01X614220Y363785D02*
X620584D01*
G01X590400Y423155D02*
Y421200D01*
G01X591215Y423970D02*
X590400Y423155D01*
G01X594554Y417046D02*
X590400Y421200D01*
G01X599400Y417046D02*
X594554D01*
G01X593060Y423970D02*
X591215D01*
G01X595420Y426330D02*
X593060Y423970D01*
G01X595420Y426720D02*
Y426330D01*
G01Y430420D02*
Y426720D01*
G01X595440Y430440D02*
X595420Y430420D01*
G01X637366Y43747D02*
Y47468D01*
G01X640144Y40969D02*
X637366Y43747D01*
G01X666264Y42436D02*
X660692D01*
G01X667900Y40800D02*
X666264Y42436D01*
G01X646811Y44189D02*
Y47468D01*
G01X648564Y42436D02*
X646811Y44189D01*
G01X660692Y42436D02*
X648564D01*
G01X643661Y21918D02*
Y25268D01*
G01X647103Y18476D02*
X643661Y21918D01*
G01X647103Y13964D02*
Y18476D01*
G01X640516Y47468D02*
Y51558D01*
G01X645236Y44723D02*
Y47468D01*
G01X644700Y44187D02*
X645236Y44723D01*
G01X644700Y35893D02*
Y44187D01*
G01X640416Y31609D02*
X644700Y35893D01*
G01X643816Y30124D02*
Y31573D01*
G01X645236Y28704D02*
X643816Y30124D01*
G01X645236Y25268D02*
Y28704D01*
G01X664301Y35315D02*
Y40104D01*
G01X663152Y49998D02*
X664301D01*
G01X656500Y56650D02*
X663152Y49998D01*
G01X646811Y29569D02*
Y25268D01*
G01X647216Y29974D02*
X646811Y29569D01*
G01X647216Y31601D02*
Y29974D01*
G01X643103Y19647D02*
Y17648D01*
G01X642091Y20659D02*
X643103Y19647D01*
G01X642091Y25268D02*
Y20659D01*
G01X643103Y17648D02*
Y13803D01*
G01X643661Y51111D02*
X644151Y51601D01*
G01X643661Y47468D02*
Y51111D01*
G01X638941Y22324D02*
Y25268D01*
G01X648386Y47468D02*
Y58641D01*
G01X638103Y13100D02*
Y16800D01*
G01Y18634D02*
Y16800D01*
G01X640516Y21047D02*
X638103Y18634D01*
G01X640516Y25268D02*
Y21047D01*
G01X635791Y29241D02*
Y25268D01*
G01X642091Y47468D02*
Y54080D01*
G01X657416Y31839D02*
X657440Y31815D01*
G01X651456Y31839D02*
X657416D01*
G01X648386Y28769D02*
X651456Y31839D01*
G01X648386Y25268D02*
Y28769D01*
G01X664301Y31815D02*
X657440D01*
G01X639893Y53449D02*
X637700Y55642D01*
G01X639893Y52181D02*
Y53449D01*
G01X640516Y51558D02*
X639893Y52181D01*
G01X656500Y63250D02*
Y56650D01*
G01X644151Y55349D02*
X642000Y57500D01*
G01X644151Y51601D02*
Y55349D01*
G01X648386Y58641D02*
X645078Y61949D01*
G01X641003Y66024D02*
Y68809D01*
G01X645078Y61949D02*
X641003Y66024D01*
G01X638229Y57942D02*
X636943D01*
G01X642091Y54080D02*
X638229Y57942D01*
G01X643306Y174803D02*
X640509Y177600D01*
G01X643307Y174803D02*
X643306D01*
G01X646456Y162160D02*
Y162204D01*
G01X645150Y160854D02*
X646456Y162160D01*
G01Y155905D02*
X648031Y157480D01*
G01X659055Y155905D02*
X657480Y154330D01*
G01X659055Y171653D02*
X660629Y173227D01*
G01X640125Y174835D02*
X643307Y171653D01*
G01X637343Y174835D02*
X640125D01*
G01X651181Y154330D02*
X652756Y155905D01*
G01X659055Y168504D02*
X660629Y170078D01*
G01X659055Y159055D02*
X660630Y160630D01*
G01X642994Y156218D02*
X643307Y155905D01*
G01X640775Y156218D02*
X642994D01*
G01X649605Y168504D02*
X649606D01*
G01X648031Y170078D02*
X649605Y168504D01*
G01X655905Y159055D02*
X654330Y157480D01*
G01X646456Y174804D02*
Y174803D01*
G01X644882Y176378D02*
X646456Y174804D01*
G01X643307Y162204D02*
X642657Y162854D01*
G01X640996Y168504D02*
X643307D01*
G01X638165Y171335D02*
X640996Y168504D01*
G01X637343Y171335D02*
X638165D01*
G01X646456Y171654D02*
Y171653D01*
G01X644882Y173228D02*
X646456Y171654D01*
G01Y168504D02*
X644882Y170078D01*
G01X677035Y215211D02*
X675264Y216982D01*
G01X677035Y209309D02*
Y215211D01*
G01X678452Y207892D02*
X677035Y209309D01*
G01X678452Y203649D02*
Y207892D01*
G01X677952Y203149D02*
X678452Y203649D01*
G01X681042Y203209D02*
X681102Y203149D01*
G01X681042Y209071D02*
Y203209D01*
G01X681102Y209131D02*
X681042Y209071D01*
G01X681102Y210499D02*
Y209131D01*
G01X681042Y210559D02*
X681102Y210499D01*
G01X681042Y212608D02*
Y210559D01*
G01X681050Y212616D02*
X681042Y212608D01*
G01X681050Y213984D02*
Y212616D01*
G01X680108Y214926D02*
X681050Y213984D01*
G01X680108Y215756D02*
Y214926D01*
G01X673436Y222428D02*
X680108Y215756D01*
G01X673436Y241980D02*
Y222428D01*
G01X698452Y201602D02*
X696850Y200000D01*
G01X693700Y196849D02*
Y196850D01*
G01X693699Y196849D02*
X693700D01*
G01X692125Y198423D02*
X693699Y196849D01*
G01X678500Y223022D02*
Y227500D01*
G01X686225Y215297D02*
X678500Y223022D01*
G01X686225Y210346D02*
Y215297D01*
G01X689201Y207370D02*
X686225Y210346D01*
G01X689201Y198200D02*
Y207370D01*
G01X690551Y196850D02*
X689201Y198200D01*
G01X678500Y227500D02*
Y233750D01*
G01X641579Y219269D02*
Y221770D01*
G01X654555Y206293D02*
X641579Y219269D01*
G01X654555Y199214D02*
Y206293D01*
G01X655294Y198475D02*
X654555Y199214D01*
G01X656665Y198475D02*
X655294D01*
G01X657489Y197651D02*
X656665Y198475D01*
G01X657489Y196323D02*
Y197651D01*
G01X658586Y195226D02*
X657489Y196323D01*
G01X660580Y195226D02*
X658586D01*
G01X662204Y196850D02*
X660580Y195226D01*
G01X641579Y227140D02*
Y221770D01*
G01X662204Y201074D02*
Y200000D01*
G01X660452Y202826D02*
X662204Y201074D01*
G01X660452Y208883D02*
Y202826D01*
G01X654464Y214871D02*
X660452Y208883D01*
G01X654464Y217358D02*
Y214871D01*
G01Y227065D02*
Y217358D01*
G01X675437Y223256D02*
Y241152D01*
G01X682535Y216158D02*
X675437Y223256D01*
G01X682535Y214269D02*
Y216158D01*
G01X682050Y213784D02*
X682535Y214269D01*
G01X682050Y212201D02*
Y213784D01*
G01X682048Y212199D02*
X682050Y212201D01*
G01X682048Y211452D02*
Y212199D01*
G01X682452Y211048D02*
X682048Y211452D01*
G01X682452Y202492D02*
Y211048D01*
G01X681102Y201142D02*
X682452Y202492D01*
G01X681102Y200000D02*
Y201142D01*
G01X671653Y220679D02*
Y203149D01*
G01X671508Y220824D02*
X671653Y220679D01*
G01X695194Y201494D02*
X693700Y200000D01*
G01X695194Y222733D02*
Y201494D01*
G01X695600Y223139D02*
X695194Y222733D01*
G01X695600Y227500D02*
Y223139D01*
G01Y233750D02*
X691100D01*
G01X695600D02*
Y227500D01*
G01X682700Y233750D02*
Y223300D01*
G01X690551Y208228D02*
Y203149D01*
G01X688225Y210554D02*
X690551Y208228D01*
G01X688225Y216126D02*
Y210554D01*
G01X682700Y221651D02*
X688225Y216126D01*
G01X682700Y223300D02*
Y221651D01*
G01X661452Y223952D02*
Y217241D01*
G01X663110Y225610D02*
X661452Y223952D01*
G01X663110Y226925D02*
Y225610D01*
G01X661452Y214600D02*
Y217241D01*
G01X665354Y210698D02*
X661452Y214600D01*
G01X665354Y203149D02*
Y210698D01*
G01X696850Y203859D02*
Y203149D01*
G01X699350Y206359D02*
X696850Y203859D01*
G01X670135Y201631D02*
X668504Y200000D01*
G01X670135Y213641D02*
Y201631D01*
G01X669353Y214423D02*
X670135Y213641D01*
G01X669353Y224723D02*
Y214423D01*
G01X670135Y225505D02*
X669353Y224723D01*
G01X670135Y241607D02*
Y225505D01*
G01X677953Y196850D02*
X677952D01*
G01X679527Y198424D02*
X677953Y196850D01*
G01X658610Y222250D02*
X657920Y221560D01*
G01X658610Y226925D02*
Y222250D01*
G01X665354Y201142D02*
Y200000D01*
G01X663952Y202544D02*
X665354Y201142D01*
G01X663952Y209698D02*
Y202544D01*
G01X657920Y215730D02*
X663952Y209698D01*
G01X657920Y221560D02*
Y215730D01*
G01X659055Y207451D02*
Y203149D01*
G01X650684Y215822D02*
X659055Y207451D01*
G01X650684Y221630D02*
Y215822D01*
G01X650287Y222027D02*
X650684Y221630D01*
G01X650287Y227024D02*
Y222027D01*
G01X666859Y198355D02*
X665354Y196850D01*
G01X666859Y212023D02*
Y198355D01*
G01X664452Y214430D02*
X666859Y212023D01*
G01X664452Y222315D02*
Y214430D01*
G01X659055Y197756D02*
Y196850D01*
G01X657629Y199182D02*
X659055Y197756D01*
G01X657629Y206048D02*
Y199182D01*
G01X646318Y217359D02*
X657629Y206048D01*
G01X646318Y217778D02*
Y217359D01*
G01X645968Y223300D02*
Y227047D01*
G01X646318Y222950D02*
X645968Y223300D01*
G01X646318Y217778D02*
Y222950D01*
G01X677952Y200789D02*
Y200000D01*
G01X679452Y202289D02*
X677952Y200789D01*
G01X679452Y209815D02*
Y202289D01*
G01X667166Y220628D02*
Y217194D01*
G01X667353Y220815D02*
X667166Y220628D01*
G01X667353Y226882D02*
Y220815D01*
G01X667166Y214639D02*
Y217194D01*
G01X668504Y213301D02*
X667166Y214639D01*
G01X668504Y203149D02*
Y213301D01*
G01X696850Y196850D02*
X695275Y198425D01*
G01X690887Y222466D02*
X691721Y223300D01*
G01X690887Y219122D02*
Y222466D01*
G01X692381Y217628D02*
X690887Y219122D01*
G01X692381Y210758D02*
Y217628D01*
G01X693700Y209439D02*
X692381Y210758D01*
G01X693700Y203149D02*
Y209439D01*
G01X686900Y233750D02*
Y227500D01*
G01Y220280D02*
Y227500D01*
G01X690270Y216910D02*
X686900Y220280D01*
G01X690270Y210619D02*
Y216910D01*
G01X692350Y208539D02*
X690270Y210619D01*
G01X692350Y202350D02*
Y208539D01*
G01X690551Y200551D02*
X692350Y202350D01*
G01X690551Y200000D02*
Y200551D01*
G01X684756Y253300D02*
X673436Y241980D01*
G01X687800Y253300D02*
X684756D01*
G01X689764Y255264D02*
X687800Y253300D01*
G01X695375Y260875D02*
X689764Y255264D01*
G01X704707Y264647D02*
X695151Y255091D01*
G01Y255039D02*
Y255091D01*
G01X690860Y250748D02*
X695151Y255039D01*
G01X685033Y250748D02*
X690860D01*
G01X675437Y241152D02*
X685033Y250748D01*
G01X689680Y261152D02*
X670135Y241607D01*
G01X695383Y266855D02*
X689680Y261152D01*
G01X670494Y418996D02*
X670610Y418880D01*
G01X670494Y425456D02*
Y418996D01*
G01X670610Y418880D02*
X673900D01*
G01X658840Y401780D02*
Y398110D01*
G01X658820Y401800D02*
X658840Y401780D01*
G01X658601Y401800D02*
X658820D01*
G01X692480Y420610D02*
X690890Y419020D01*
G01X701325Y420610D02*
X692480D01*
G01X676250Y407500D02*
X680560D01*
G01X682995D02*
X687015Y411520D01*
G01X680560Y407500D02*
X682995D01*
G01X668150Y408770D02*
Y428110D01*
G01X661380Y402000D02*
X668150Y408770D01*
G01X661380Y397090D02*
Y402000D01*
G01X658900Y394610D02*
X661380Y397090D01*
G01X658840Y394610D02*
X658900D01*
G01X654770D02*
X658840D01*
G01X665000Y385043D02*
Y382565D01*
G01X661650Y388393D02*
X665000Y385043D01*
G01X661650Y390100D02*
Y388393D01*
G01X660350Y391400D02*
X661650Y390100D01*
G01X657980Y391400D02*
X660350D01*
G01X654770Y394610D02*
X657980Y391400D01*
G01X690690Y424820D02*
X686390D01*
G01X695360D02*
X695380Y424800D01*
G01X690690Y424820D02*
X695360D01*
G01X695380Y424800D02*
X701890D01*
G01X697200Y432800D02*
X695980D01*
G01X698100Y431900D02*
X697200Y432800D01*
G01X695380Y432200D02*
X695980Y432800D01*
G01X695380Y428300D02*
Y432200D01*
G01X683250Y433300D02*
Y437813D01*
G01X673054Y429624D02*
Y431956D01*
G01X672040Y428610D02*
X673054Y429624D01*
G01X668650Y428610D02*
X672040D01*
G01X668150Y428110D02*
X668650Y428610D01*
G01X725420Y37232D02*
Y73552D01*
G01X722834Y34646D02*
X725420Y37232D01*
G01X727448Y33748D02*
Y72444D01*
G01X722834Y29134D02*
X727448Y33748D01*
G01X707649Y113161D02*
X709448Y114960D01*
G01X707649Y110002D02*
Y113161D01*
G01X731642Y91792D02*
X731900Y92050D01*
G01X724346Y91792D02*
X731642D01*
G01X719365Y96773D02*
X724346Y91792D01*
G01X705913Y111425D02*
X706299Y111811D01*
G01X705913Y108809D02*
Y111425D01*
G01X706700Y108022D02*
X705913Y108809D01*
G01X706700Y107801D02*
Y108022D01*
G01X709339Y105162D02*
X706700Y107801D01*
G01X713135Y105162D02*
X709339D01*
G01X717525Y100772D02*
X713135Y105162D01*
G01X717525Y98613D02*
Y100772D01*
G01X719365Y96773D02*
X717525Y98613D01*
G01X742005Y107600D02*
X734645Y114960D01*
G01X749391Y107600D02*
X742005D01*
G01X751391Y109600D02*
X749391Y107600D01*
G01X754000Y109600D02*
X751391D01*
G01X727700Y113216D02*
Y114314D01*
G01X726896Y112412D02*
X727700Y113216D01*
G01X726896Y111210D02*
Y112412D01*
G01X731000Y107106D02*
X726896Y111210D01*
G01X731000Y106315D02*
Y107106D01*
G01X744551Y100815D02*
X742523D01*
G01X745000Y100366D02*
X744551Y100815D01*
G01X746864Y100366D02*
X745000D01*
G01X749430Y97800D02*
X746864Y100366D01*
G01X750950Y97800D02*
X749430D01*
G01X727792Y100815D02*
X742523D01*
G01X724900Y103707D02*
X727792Y100815D01*
G01X721521Y103707D02*
X724900D01*
G01X720130Y105098D02*
X721521Y103707D01*
G01X718859Y105098D02*
X720130D01*
G01X714950Y109007D02*
X718859Y105098D01*
G01X714950Y111013D02*
Y109007D01*
G01X715748Y111811D02*
X714950Y111013D01*
G01X751023Y97727D02*
X750950Y97800D01*
G01X751023Y93565D02*
Y97727D01*
G01X728535Y76667D02*
X747919D01*
G01X725420Y73552D02*
X728535Y76667D01*
G01X747919D02*
X786149D01*
G01X787176Y74636D02*
X750773D01*
G01X729640D02*
X750773D01*
G01X727448Y72444D02*
X729640Y74636D01*
G01X730046Y111154D02*
Y113510D01*
G01X732955Y108245D02*
X730046Y111154D01*
G01X736080Y108245D02*
X732955D01*
G01X737800Y106525D02*
X736080Y108245D01*
G01X736785Y110185D02*
X733046Y113924D01*
G01X719010Y111698D02*
Y107281D01*
G01X718897Y111811D02*
X719010Y111698D01*
G01X728346Y111354D02*
Y111811D01*
G01X732500Y107200D02*
X728346Y111354D01*
G01X734104Y107200D02*
X732500D01*
G01X734709Y106595D02*
X734104Y107200D01*
G01X721835Y111599D02*
X722047Y111811D01*
G01X721835Y109077D02*
Y111599D01*
G01X727947Y102965D02*
X721835Y109077D01*
G01X744598Y102965D02*
X727947D01*
G01X744963Y102600D02*
X744598Y102965D01*
G01X751463Y102600D02*
X744963D01*
G01X751613Y102750D02*
X751463Y102600D01*
G01X755298Y102750D02*
X751613D01*
G01X759023Y99025D02*
X755298Y102750D01*
G01X759023Y97440D02*
Y99025D01*
G01X758052Y93565D02*
X755523D01*
G01X759023Y94536D02*
X758052Y93565D01*
G01X759023Y97440D02*
Y94536D01*
G01X720697Y107420D02*
Y113610D01*
G01X722673Y105444D02*
X720697Y107420D01*
G01X758770Y112000D02*
X761770Y115000D01*
G01X746000Y112000D02*
X758770D01*
G01X744700Y110700D02*
X746000Y112000D01*
G01X742600Y110700D02*
X744700D01*
G01X735190Y118110D02*
X742600Y110700D01*
G01X723485Y113249D02*
X725196Y114960D01*
G01X723485Y111315D02*
Y113249D01*
G01X726100Y108700D02*
X723485Y111315D01*
G01X726100Y107200D02*
Y108700D01*
G01X722459Y84955D02*
X726039D01*
G01X716216Y91198D02*
X722459Y84955D01*
G01X716216Y99684D02*
Y91198D01*
G01X711935Y103965D02*
X716216Y99684D01*
G01X709035Y103965D02*
X711935D01*
G01X707388Y105612D02*
X709035Y103965D01*
G01X704154Y105612D02*
X707388D01*
G01X703149Y106617D02*
X704154Y105612D01*
G01X703149Y111811D02*
Y106617D01*
G01X739550Y86300D02*
X739450Y86200D01*
G01X743450Y86300D02*
X739550D01*
G01X739450Y84550D02*
Y86200D01*
G01X738300Y83400D02*
X739450Y84550D01*
G01X727594Y83400D02*
X738300D01*
G01X726039Y84955D02*
X727594Y83400D01*
G01X723285Y81300D02*
X761200D01*
G01X714216Y90369D02*
X723285Y81300D01*
G01X714216Y99222D02*
Y90369D01*
G01X710721Y102717D02*
X714216Y99222D01*
G01X708868Y102717D02*
X710721D01*
G01X706973Y104612D02*
X708868Y102717D01*
G01X703739Y104612D02*
X706973D01*
G01X701799Y106552D02*
X703739Y104612D01*
G01X701799Y113610D02*
Y106552D01*
G01X744050Y112650D02*
X745400Y114000D01*
G01X742250Y112650D02*
X744050D01*
G01X735085Y119815D02*
X742250Y112650D01*
G01X732396Y111811D02*
X734212Y109995D01*
G01X731496Y111811D02*
X732396D01*
G01X712950Y111459D02*
X712598Y111811D01*
G01X712950Y108177D02*
Y111459D01*
G01X718029Y103098D02*
X712950Y108177D01*
G01X719016Y103098D02*
X718029D01*
G01X720435Y101679D02*
X719016Y103098D01*
G01X722025Y101679D02*
X720435D01*
G01X727161Y96543D02*
X722025Y101679D01*
G01X734286Y96543D02*
X727161D01*
G01X735229Y95600D02*
X734286Y96543D01*
G01X737100Y95600D02*
X735229D01*
G01X740700Y94500D02*
X743450D01*
G01X739600Y95600D02*
X740700Y94500D01*
G01X737100Y95600D02*
X739600D01*
G01X742220Y109550D02*
X735110Y116660D01*
G01X745800Y109550D02*
X742220D01*
G01X746000Y109750D02*
X745800Y109550D01*
G01X748500Y109750D02*
X746000D01*
G01X704849Y107385D02*
Y113510D01*
G01X709448Y107892D02*
Y111811D01*
G01X710517Y106823D02*
X709448Y107892D01*
G01X717197Y113260D02*
X718897Y114960D01*
G01X717197Y109646D02*
Y113260D01*
G01X726727Y94148D02*
X727727D01*
G01X720919Y99956D02*
X726727Y94148D01*
G01X719756Y99956D02*
X720919D01*
G01X711248Y108464D02*
X719756Y99956D01*
G01X711248Y113610D02*
Y108464D01*
G01X729204Y94148D02*
X727727D01*
G01X729599Y94543D02*
X729204Y94148D01*
G01X733457Y94543D02*
X729599D01*
G01X734700Y93300D02*
X733457Y94543D01*
G01X737850Y93300D02*
X734700D01*
G01X739450Y91700D02*
X737850Y93300D01*
G01X739450Y90300D02*
Y91700D01*
G01X741547Y90400D02*
X743450D01*
G01X741447Y90300D02*
X741547Y90400D01*
G01X739450Y90300D02*
X741447D01*
G01X718897Y118110D02*
X717322Y116535D01*
G01X735289Y126915D02*
X734645Y127559D01*
G01X738393Y126915D02*
X735289D01*
G01X745308Y120000D02*
X738393Y126915D01*
G01X754500Y120000D02*
X745308D01*
G01X760500Y126000D02*
X754500Y120000D01*
G01X703149Y127559D02*
X704723Y129133D01*
G01X728347Y159055D02*
X728346D01*
G01X729921Y160629D02*
X728347Y159055D01*
G01X728346Y124409D02*
X729921Y122834D01*
G01X738164Y174803D02*
X734645D01*
G01X738352Y174615D02*
X738164Y174803D01*
G01X725196Y118109D02*
Y118110D01*
G01X723622Y116535D02*
X725196Y118109D01*
G01X755658Y118000D02*
X763458Y125800D01*
G01X744935Y118000D02*
X755658D01*
G01X737020Y125915D02*
X744935Y118000D01*
G01X733140Y125915D02*
X737020D01*
G01X731496Y127559D02*
X733140Y125915D01*
G01X715748Y118110D02*
X714173Y116535D01*
G01X731496Y171653D02*
X733070Y170079D01*
G01X728347Y146456D02*
X728346D01*
G01X729921Y144882D02*
X728347Y146456D01*
G01X747306Y151350D02*
X760100D01*
G01X744856Y153800D02*
X747306Y151350D01*
G01X741973Y153800D02*
X744856D01*
G01X741218Y154555D02*
X741973Y153800D01*
G01X734078Y154555D02*
X741218D01*
G01X732728Y155905D02*
X734078Y154555D01*
G01X731496Y155905D02*
X732728D01*
G01X727700Y114314D02*
X728346Y114960D01*
G01X709448Y171653D02*
X711023Y173228D01*
G01X728346Y155905D02*
X729921Y157480D01*
G01X728346Y162204D02*
X729921Y163779D01*
G01X728346Y165354D02*
X726771Y163779D01*
G01X732608Y133858D02*
X731496D01*
G01X734173Y132293D02*
X732608Y133858D01*
G01X737808Y132293D02*
X734173D01*
G01X742998Y127103D02*
X737808Y132293D01*
G01X742998Y125115D02*
Y127103D01*
G01X746113Y122000D02*
X742998Y125115D01*
G01X753041Y122000D02*
X746113D01*
G01X759341Y128300D02*
X753041Y122000D01*
G01X751250Y138650D02*
X753050D01*
G01X749239Y140661D02*
X751250Y138650D01*
G01X745414Y140661D02*
X749239D01*
G01X738006Y148069D02*
X745414Y140661D01*
G01X733033Y148069D02*
X738006D01*
G01X731496Y149606D02*
X733033Y148069D01*
G01X755200Y138650D02*
X758450Y135400D01*
G01X753050Y138650D02*
X755200D01*
G01X733146Y135358D02*
X731496Y137008D01*
G01X738160Y135358D02*
X733146D01*
G01X740816Y132702D02*
X738160Y135358D01*
G01X742089Y132702D02*
X740816D01*
G01X743999Y130792D02*
X742089Y132702D01*
G01X743999Y129772D02*
Y130792D01*
G01X747521Y126250D02*
X743999Y129772D01*
G01X749200Y126250D02*
X747521D01*
G01X732735Y159055D02*
X731496D01*
G01X734121Y157669D02*
X732735Y159055D01*
G01X746719Y157669D02*
X734121D01*
G01X746750Y157700D02*
X746719Y157669D01*
G01X730046Y113510D02*
X731496Y114960D01*
G01X749680Y169550D02*
X753550D01*
G01X735832Y162204D02*
X734645D01*
G01X741554Y167926D02*
X735832Y162204D01*
G01X745746Y167926D02*
X741554D01*
G01X747370Y169550D02*
X745746Y167926D01*
G01X749680Y169550D02*
X747370D01*
G01X756900Y116000D02*
X760450Y119550D01*
G01X744971Y116000D02*
X756900D01*
G01X743921Y117050D02*
X744971Y116000D01*
G01X741217Y117050D02*
X743921D01*
G01X735491Y122776D02*
X741217Y117050D01*
G01X733614Y122776D02*
X735491D01*
G01X731981Y124409D02*
X733614Y122776D01*
G01X731496Y124409D02*
X731981D01*
G01X738013Y133858D02*
X734645D01*
G01X743999Y127872D02*
X738013Y133858D01*
G01X743999Y126943D02*
Y127872D01*
G01X746942Y124000D02*
X743999Y126943D01*
G01X751750Y124000D02*
X746942D01*
G01X754000Y126250D02*
X751750Y124000D01*
G01X741152Y173115D02*
X741952D01*
G01X741002Y172965D02*
X741152Y173115D01*
G01X737668Y172965D02*
X741002D01*
G01X737180Y173453D02*
X737668Y172965D01*
G01X732846Y173453D02*
X737180D01*
G01X731496Y174803D02*
X732846Y173453D01*
G01X751990Y183153D02*
X741952Y173115D01*
G01X729426Y118110D02*
X728346D01*
G01X730990Y116546D02*
X729426Y118110D01*
G01X731961Y116546D02*
X730990D01*
G01X733046Y115461D02*
X731961Y116546D01*
G01X733046Y113924D02*
Y115461D01*
G01X728346Y174803D02*
X729920Y173229D01*
G01X712598Y127559D02*
X714172Y129133D01*
G01X728347Y130708D02*
X728346D01*
G01X729921Y129134D02*
X728347Y130708D01*
G01X744906Y144841D02*
X745351Y144396D01*
G01X743249Y144841D02*
X744906D01*
G01X738484Y149606D02*
X743249Y144841D01*
G01X734645Y149606D02*
X738484D01*
G01X747052Y142695D02*
X745351Y144396D01*
G01X750205Y142695D02*
X747052D01*
G01X751550Y141350D02*
X750205Y142695D01*
G01X755550Y141350D02*
X751550D01*
G01X757400Y139500D02*
X755550Y141350D01*
G01X735110Y121260D02*
X734645D01*
G01X741670Y114700D02*
X735110Y121260D01*
G01X743100Y114700D02*
X741670D01*
G01X736781Y146456D02*
X734645D01*
G01X737352Y145885D02*
X736781Y146456D01*
G01X700000Y127559D02*
X701574Y129133D01*
G01X751855Y144695D02*
X752700Y143850D01*
G01X748303Y144695D02*
X751855D01*
G01X745999Y146999D02*
X748303Y144695D01*
G01X743083Y146999D02*
X745999D01*
G01X738676Y151406D02*
X743083Y146999D01*
G01X733472Y151406D02*
X738676D01*
G01X732122Y152756D02*
X733472Y151406D01*
G01X731496Y152756D02*
X732122D01*
G01X752926Y143624D02*
X752700Y143850D01*
G01X757421Y143624D02*
X752926D01*
G01X703149Y118110D02*
X701575Y116536D01*
G01X706299Y127559D02*
X707873Y129133D01*
G01X740708Y171417D02*
X734645Y165354D01*
G01X742767Y171417D02*
X740708D01*
G01X746510Y175160D02*
X742767Y171417D01*
G01X747860Y175160D02*
X746510D01*
G01X751753Y179053D02*
X747860Y175160D01*
G01X709448Y118109D02*
Y118110D01*
G01X707874Y116535D02*
X709448Y118109D01*
G01X728346Y133858D02*
X729921Y132283D01*
G01X733295Y144657D02*
X731496Y146456D01*
G01X735205Y144657D02*
X733295D01*
G01X736047Y143815D02*
X735205Y144657D01*
G01X740809Y143815D02*
X736047D01*
G01X741824Y142800D02*
X740809Y143815D01*
G01X741860Y142800D02*
X741824D01*
G01X746330Y138330D02*
X741860Y142800D01*
G01X748000Y138330D02*
X746330D01*
G01X748000Y138000D02*
Y138330D01*
G01X750550Y135450D02*
X748000Y138000D01*
G01X750550Y135200D02*
Y135450D01*
G01X739622Y137008D02*
X734645D01*
G01X720697Y113610D02*
X722047Y114960D01*
G01X734645Y118110D02*
X735190D01*
G01X734645Y171653D02*
X736219Y170079D01*
G01X743012Y149600D02*
X745700D01*
G01X739856Y152756D02*
X743012Y149600D01*
G01X734645Y152756D02*
X739856D01*
G01X746227Y149600D02*
X745700D01*
G01X747582Y148245D02*
X746227Y149600D01*
G01X750373Y148245D02*
X747582D01*
G01X737978Y130708D02*
X734645D01*
G01X740200Y128486D02*
X737978Y130708D01*
G01X740200Y127567D02*
Y128486D01*
G01X740952Y126815D02*
X740200Y127567D01*
G01X712598Y118110D02*
X711023Y116535D01*
G01X732735Y140157D02*
X731496D01*
G01X734092Y138800D02*
X732735Y140157D01*
G01X740164Y138800D02*
X734092D01*
G01X741272Y137692D02*
X740164Y138800D01*
G01X741272Y135099D02*
Y137692D01*
G01X741754Y134617D02*
X741272Y135099D01*
G01X703149Y114960D02*
X701799Y113610D01*
G01X757941Y114000D02*
X763441Y119500D01*
G01X745400Y114000D02*
X757941D01*
G01X732941Y119815D02*
X735085D01*
G01X731496Y121260D02*
X732941Y119815D01*
G01X732988Y141815D02*
X731496Y143307D01*
G01X739979Y141815D02*
X732988D01*
G01X743300Y138494D02*
X739979Y141815D01*
G01X743300Y136915D02*
Y138494D01*
G01X745050Y135165D02*
X743300Y136915D01*
G01X745050Y134671D02*
Y135165D01*
G01X748671Y131050D02*
X745050Y134671D01*
G01X750400Y131050D02*
X748671D01*
G01X728346Y137008D02*
X729921Y135433D01*
G01X709448Y127559D02*
X711022Y129133D01*
G01X728346Y149606D02*
X729921Y148031D01*
G01X732904Y129300D02*
X731496Y130708D01*
G01X736967Y129300D02*
X732904D01*
G01X737702Y128565D02*
X736967Y129300D01*
G01X728346Y143307D02*
X729921Y141732D01*
G01X732227Y118110D02*
X731496D01*
G01X733677Y116660D02*
X732227Y118110D01*
G01X735110Y116660D02*
X733677D01*
G01X752100Y157200D02*
X765615D01*
G01X750358Y155458D02*
X752100Y157200D01*
G01X750358Y154100D02*
Y155458D01*
G01X745604Y155905D02*
X734645D01*
G01X747409Y154100D02*
X745604Y155905D01*
G01X750358Y154100D02*
X747409D01*
G01X704849Y113510D02*
X706299Y114960D01*
G01X728347Y152756D02*
X728346D01*
G01X729921Y154330D02*
X728347Y152756D01*
G01X735137Y142815D02*
X734645Y143307D01*
G01X740394Y142815D02*
X735137D01*
G01X744300Y138909D02*
X740394Y142815D01*
G01X744300Y137531D02*
Y138909D01*
G01X745501Y136330D02*
X744300Y137531D01*
G01X746220Y136330D02*
X745501D01*
G01X749250Y133300D02*
X746220Y136330D01*
G01X753150Y133300D02*
X749250D01*
G01X755300Y131150D02*
X753150Y133300D01*
G01X743283Y161832D02*
X744300Y160815D01*
G01X739393Y161832D02*
X743283D01*
G01X736616Y159055D02*
X739393Y161832D01*
G01X734645Y159055D02*
X736616D01*
G01X745065Y160050D02*
X744300Y160815D01*
G01X750350Y160050D02*
X745065D01*
G01X747100Y165300D02*
X747350Y165050D01*
G01X740795Y165300D02*
X747100D01*
G01X736293Y160798D02*
X740795Y165300D01*
G01X732902Y160798D02*
X736293D01*
G01X731496Y162204D02*
X732902Y160798D01*
G01X748319Y164081D02*
X751218D01*
G01X747350Y165050D02*
X748319Y164081D01*
G01X755910Y166800D02*
X760000D01*
G01X755879Y166831D02*
X755910Y166800D01*
G01X752168Y166831D02*
X755879D01*
G01X751218Y165881D02*
X752168Y166831D01*
G01X751218Y164081D02*
Y165881D01*
G01X728346Y127559D02*
X729921Y125984D01*
G01X712598Y114960D02*
X711248Y113610D01*
G01X758200Y130300D02*
X759500D01*
G01X756800Y128900D02*
X758200Y130300D01*
G01X747700Y128900D02*
X756800D01*
G01X745750Y130850D02*
X747700Y128900D01*
G01X745750Y131637D02*
Y130850D01*
G01X744050Y133337D02*
X745750Y131637D01*
G01X744050Y134750D02*
Y133337D01*
G01X742300Y136500D02*
X744050Y134750D01*
G01X742300Y138079D02*
Y136500D01*
G01X740579Y139800D02*
X742300Y138079D01*
G01X740473Y139800D02*
X740579D01*
G01X740116Y140157D02*
X740473Y139800D01*
G01X734645Y140157D02*
X740116D01*
G01X728346D02*
X729921Y138582D01*
G01X728346Y121260D02*
X726771Y122835D01*
G01X736192Y124409D02*
X734645D01*
G01X739952Y120649D02*
X736192Y124409D01*
G01X744955Y170076D02*
X744552D01*
G01X747979Y173100D02*
X744955Y170076D01*
G01X749480Y173100D02*
X747979D01*
G01X750095Y173715D02*
X749480Y173100D01*
G01X753552Y173715D02*
X750095D01*
G01X741531Y170076D02*
X744552D01*
G01X735459Y164004D02*
X741531Y170076D01*
G01X733744Y164004D02*
X735459D01*
G01X732394Y165354D02*
X733744Y164004D01*
G01X731496Y165354D02*
X732394D01*
G01X734645Y177952D02*
X737315D01*
G01X700000Y200037D02*
Y200000D01*
G01X701350Y201387D02*
X700000Y200037D01*
G01X701350Y204568D02*
Y201387D01*
G01X703477Y206695D02*
X701350Y204568D01*
G01X703477Y213477D02*
Y206695D01*
G01X704000Y214000D02*
X703477Y213477D01*
G01X704000Y217740D02*
Y214000D01*
G01X712720Y226460D02*
X704000Y217740D01*
G01X712720Y229666D02*
Y226460D01*
G01Y234372D02*
Y229666D01*
G01X698452Y203660D02*
Y201602D01*
G01X701500Y206708D02*
X698452Y203660D01*
G01X701500Y219000D02*
Y206708D01*
G01X732996Y192200D02*
X731496Y193700D01*
G01X736137Y192200D02*
X732996D01*
G01X739852Y195915D02*
X736137Y192200D01*
G01X738845Y197900D02*
X734645Y193700D01*
G01X741712Y197900D02*
X738845D01*
G01X745485Y201673D02*
X741712Y197900D01*
G01X731516Y190551D02*
X731496D01*
G01X733167Y188900D02*
X731516Y190551D01*
G01X739168Y188900D02*
X733167D01*
G01X744052Y193784D02*
X739168Y188900D01*
G01X709448Y196850D02*
X711023Y198425D01*
G01X715748Y196851D02*
Y196850D01*
G01X717322Y198425D02*
X715748Y196851D01*
G01X735671Y202912D02*
X738839Y206080D01*
G01X735671Y201026D02*
Y202912D01*
G01X734645Y200000D02*
X735671Y201026D01*
G01X738959Y206200D02*
X753580D01*
G01X738839Y206080D02*
X738959Y206200D01*
G01X728346Y200946D02*
Y200000D01*
G01X729796Y202396D02*
X728346Y200946D01*
G01X729796Y204896D02*
Y202396D01*
G01X729136Y205556D02*
X729796Y204896D01*
G01X729136Y206654D02*
Y205556D01*
G01X736498Y213848D02*
X743600Y220950D01*
G01X734784Y213848D02*
X736498D01*
G01X730896Y209960D02*
X734784Y213848D01*
G01X730896Y208414D02*
Y209960D01*
G01X729136Y206654D02*
X730896Y208414D01*
G01X738915Y184252D02*
X734645D01*
G01X738952Y184215D02*
X738915Y184252D01*
G01X717400Y201497D02*
X718897Y200000D01*
G01X717400Y203468D02*
Y201497D01*
G01X715467Y205401D02*
X717400Y203468D01*
G01X715467Y210507D02*
Y205401D01*
G01X725678Y217450D02*
X719300D01*
G01X725750Y217522D02*
X725678Y217450D01*
G01X715467Y213617D02*
Y210507D01*
G01X719300Y217450D02*
X715467Y213617D01*
G01X703149Y196850D02*
X704724Y198425D01*
G01X743466Y187401D02*
X734645D01*
G01X743752Y187115D02*
X743466Y187401D01*
G01X748644Y189673D02*
Y191051D01*
G01X744436Y185465D02*
X748644Y189673D01*
G01X741375Y185465D02*
X744436D01*
G01X740901Y185939D02*
X741375Y185465D01*
G01X732958Y185939D02*
X740901D01*
G01X731496Y187401D02*
X732958Y185939D01*
G01X748644Y194514D02*
Y191051D01*
G01X745485Y197673D02*
X748644Y194514D01*
G01X706299Y196850D02*
X707873Y198424D01*
G01X730703Y228448D02*
X726656D01*
G01X730712Y228457D02*
X730703Y228448D01*
G01X728595Y226340D02*
X730703Y228448D01*
G01X728595Y216878D02*
Y226340D01*
G01X725009Y213292D02*
X728595Y216878D01*
G01X723570Y201626D02*
X725196Y200000D01*
G01X723570Y207725D02*
Y201626D01*
G01X723092Y208203D02*
X723570Y207725D01*
G01X723092Y211375D02*
Y208203D01*
G01X725009Y213292D02*
X723092Y211375D01*
G01X700000Y196850D02*
X701574Y198424D01*
G01X739786Y182715D02*
X742502D01*
G01X739636Y182565D02*
X739786Y182715D01*
G01X733183Y182565D02*
X739636D01*
G01X731496Y184252D02*
X733183Y182565D01*
G01X722047Y208572D02*
Y203149D01*
G01X720819Y209800D02*
X722047Y208572D01*
G01X712598Y196850D02*
X714173Y198425D01*
G01X736321Y208181D02*
X736272D01*
G01X738340Y210200D02*
X736321Y208181D01*
G01X753580Y210200D02*
X738340D01*
G01X729996Y198500D02*
X728346Y196850D01*
G01X732047Y198500D02*
X729996D01*
G01X733100Y199553D02*
X732047Y198500D01*
G01X733100Y200676D02*
Y199553D01*
G01X734671Y202247D02*
X733100Y200676D01*
G01X734671Y206531D02*
Y202247D01*
G01X736272Y208132D02*
X734671Y206531D01*
G01X736272Y208181D02*
Y208132D01*
G01X728346Y181102D02*
X729921Y179527D01*
G01X699350Y221321D02*
Y206359D01*
G01X701500Y223471D02*
X699350Y221321D01*
G01X701500Y225500D02*
Y223471D01*
G01Y228655D02*
Y225500D01*
G01X699600Y230555D02*
X701500Y228655D01*
G01X699600Y233750D02*
Y230555D01*
G01X718897Y204605D02*
Y203149D01*
G01X718330Y205172D02*
X718897Y204605D01*
G01X752490Y187253D02*
X742252Y177015D01*
G01X753568Y187253D02*
X752490D01*
G01X741537Y176300D02*
X742252Y177015D01*
G01X733148Y176300D02*
X741537D01*
G01X731496Y177952D02*
X733148Y176300D01*
G01X753568Y183153D02*
X751990D01*
G01X711100Y201652D02*
X709448Y200000D01*
G01X711100Y204820D02*
Y201652D01*
G01X711310Y205030D02*
X711100Y204820D01*
G01X711310Y207023D02*
Y205030D01*
G01X733565Y203167D02*
Y210184D01*
G01X731496Y201098D02*
X733565Y203167D01*
G01X731496Y200000D02*
Y201098D01*
G01X749197Y214200D02*
X753580D01*
G01X747407Y212410D02*
X749197Y214200D01*
G01X735791Y212410D02*
X747407D01*
G01X733565Y210184D02*
X735791Y212410D01*
G01X720643Y201404D02*
X722047Y200000D01*
G01X720643Y206818D02*
Y201404D01*
G01X720357Y207104D02*
X720643Y206818D01*
G01X715748Y203149D02*
X714173Y201574D01*
G01X718897Y196850D02*
X720471Y198424D01*
G01X728346Y177952D02*
X729920Y176378D01*
G01X753568Y179053D02*
X751753D01*
G01X753568Y178282D02*
Y179053D01*
G01X755350Y176500D02*
X753568Y178282D01*
G01X770351Y176500D02*
X755350D01*
G01X735550Y196850D02*
X734645D01*
G01X738315Y199615D02*
X735550Y196850D01*
G01X739752Y199615D02*
X738315D01*
G01X737832Y201136D02*
Y202664D01*
G01X735196Y198500D02*
X737832Y201136D01*
G01X734100Y198500D02*
X735196D01*
G01X732450Y196850D02*
X734100Y198500D01*
G01X731496Y196850D02*
X732450D01*
G01X753580Y197200D02*
Y201700D01*
G01X751380Y203900D02*
X753580Y201700D01*
G01X739068Y203900D02*
X751380D01*
G01X737832Y202664D02*
X739068Y203900D01*
G01X728346Y190551D02*
X729920Y188977D01*
G01X728346Y193700D02*
X729920Y192126D01*
G01X703150Y200000D02*
X703149D01*
G01X704724Y201574D02*
X703150Y200000D01*
G01X737375Y223075D02*
X739500Y220950D01*
G01X737375Y226255D02*
Y223075D01*
G01X738786Y227666D02*
X737375Y226255D01*
G01X738786Y228473D02*
Y227666D01*
G01X729246Y210696D02*
X739500Y220950D01*
G01X729246Y209941D02*
Y210696D01*
G01Y209349D02*
Y209941D01*
G01X727402Y207505D02*
X729246Y209349D01*
G01X727402Y205538D02*
Y207505D01*
G01X728346Y204594D02*
X727402Y205538D01*
G01X728346Y203149D02*
Y204594D01*
G01X731496Y181101D02*
Y181102D01*
G01X733070Y179527D02*
X731496Y181101D01*
G01X726546Y198200D02*
X725196Y196850D01*
G01X726546Y204550D02*
Y198200D01*
G01X724776Y206320D02*
X726546Y204550D01*
G01X724776Y209963D02*
Y206320D01*
G01X734286Y219473D02*
X724776Y209963D01*
G01X734286Y220973D02*
Y219473D01*
G01X728346Y187401D02*
X729920Y185827D01*
G01X731496Y205891D02*
Y203149D01*
G01X731915Y206310D02*
X731496Y205891D01*
G01X722047Y196850D02*
X723621Y198424D01*
G01X707852Y201553D02*
X706299Y200000D01*
G01X707852Y204390D02*
Y201553D01*
G01X706737Y205505D02*
X707852Y204390D01*
G01X711750Y217500D02*
X707000D01*
G01X709448Y207500D02*
Y203149D01*
G01X707000Y209948D02*
X709448Y207500D01*
G01X707000Y217500D02*
Y209948D01*
G01X735632Y180115D02*
X734645Y181102D01*
G01X740352Y180115D02*
X735632D01*
G01X728346Y184252D02*
X729920Y182678D01*
G01X704527Y204921D02*
X706299Y203149D01*
G01X704527Y207628D02*
Y204921D01*
G01X705336Y208437D02*
X704527Y207628D01*
G01X734645Y190551D02*
X738416D01*
G01X747220Y301620D02*
Y297120D01*
G01X704708Y264647D02*
X704707D01*
G01X759087Y282134D02*
X762337D01*
G01X758065Y283156D02*
X759087Y282134D01*
G01X758065Y286395D02*
Y283156D01*
G01X759300Y287630D02*
X758065Y286395D01*
G01X763292Y287630D02*
X759300D01*
G01X749970Y304370D02*
X747220Y301620D01*
G01X754220Y304370D02*
X749970D01*
G01X755574Y305724D02*
X754220Y304370D01*
G01X757483Y305724D02*
X755574D01*
G01X759586D02*
X757483D01*
G01X757633Y321684D02*
Y317184D01*
G01X762329D02*
X757633D01*
G01X755774Y310924D02*
X757483D01*
G01X752120Y307270D02*
X755774Y310924D01*
G01X751470Y307270D02*
X752120D01*
G01X746970D02*
X751470D01*
G01X757483Y310924D02*
X759866D01*
G01X704475Y423760D02*
X701325Y420610D01*
G01X709765Y423760D02*
X704475D01*
G01X715975Y429970D02*
X709765Y423760D01*
G01X743160Y425460D02*
Y428240D01*
G01X741600Y423900D02*
X743160Y425460D01*
G01X739680Y423900D02*
X741600D01*
G01X743480Y430150D02*
Y432140D01*
G01X743160Y429830D02*
X743480Y430150D01*
G01X743160Y428240D02*
Y429830D01*
G01X738320Y428730D02*
X739070Y427980D01*
G01X738320Y429120D02*
Y428730D01*
G01X737915Y429525D02*
X738320Y429120D01*
G01X737915Y433840D02*
Y429525D01*
G01X739070Y424510D02*
X739680Y423900D01*
G01X739070Y427980D02*
Y424510D01*
G01X701890Y424800D02*
X705200Y428110D01*
G01X698100Y429474D02*
Y431900D01*
G01X700855Y426719D02*
X698100Y429474D01*
G01X724340Y447430D02*
Y443410D01*
G01Y437617D02*
Y443410D01*
G01X719443Y432720D02*
X724340Y437617D01*
G01X718725Y432720D02*
X719443D01*
G01X715975Y429970D02*
X718725Y432720D01*
G01X710200Y434480D02*
X706120D01*
G01X713100Y437380D02*
X710200Y434480D01*
G01X713100Y441200D02*
Y437380D01*
G01X714400Y442500D02*
X713100Y441200D01*
G01X714820Y442500D02*
X714400D01*
G01X719850Y437470D02*
X714820Y442500D01*
G01X792802Y83320D02*
Y131493D01*
G01X786149Y76667D02*
X792802Y83320D01*
G01X794802Y82262D02*
X787176Y74636D01*
G01X794802Y131259D02*
Y82262D01*
G01X783489Y84511D02*
X784767D01*
G01X781850Y86150D02*
X783489Y84511D01*
G01X766050Y86150D02*
X781850D01*
G01X761200Y81300D02*
X766050Y86150D01*
G01X786711Y84511D02*
X784767D01*
G01X788287Y86087D02*
X786711Y84511D01*
G01X763458Y125800D02*
X765800D01*
G01X768900Y142550D02*
Y134800D01*
G01X760100Y151350D02*
X768900Y142550D01*
G01X791765Y132530D02*
Y187137D01*
G01X792802Y131493D02*
X791765Y132530D01*
G01X762400Y128300D02*
X759341D01*
G01X764900Y130800D02*
X762400Y128300D01*
G01X796400Y132857D02*
X794802Y131259D01*
G01X796400Y138864D02*
Y132857D01*
G01X793765Y141499D02*
X796400Y138864D01*
G01X793765Y186308D02*
Y141499D01*
G01X761770Y115000D02*
X763500D01*
G01X763441Y119500D02*
X765500D01*
G01X786350Y173450D02*
Y178950D01*
G01X770100Y157200D02*
X786350Y173450D01*
G01X765615Y157200D02*
X770100D01*
G01X762550Y164250D02*
Y164200D01*
G01X760000Y166800D02*
X762550Y164250D01*
G01X759500Y130300D02*
X760100Y130900D01*
G01X798400Y210898D02*
X801618Y214116D01*
G01X798400Y193772D02*
Y210898D01*
G01X791765Y187137D02*
X798400Y193772D01*
G01X801618Y194161D02*
X793765Y186308D01*
G01X801618Y210116D02*
Y194161D01*
G01X777050Y176500D02*
X770351D01*
G01X779200Y178650D02*
X777050Y176500D01*
G01X786350Y178950D02*
X786400Y179000D01*
G01X793837Y287696D02*
X801934D01*
G01X761639Y303671D02*
X759586Y305724D01*
G01X765018Y303671D02*
X761639D01*
G01X777169Y306231D02*
X781198D01*
G01X773000Y310400D02*
X777169Y306231D01*
G01X773000Y315800D02*
Y310400D01*
G01X781198Y301111D02*
X789658D01*
G01X793394Y302620D02*
X794720D01*
G01X791885Y301111D02*
X793394Y302620D01*
G01X789658Y301111D02*
X791885D01*
G01X799748Y302620D02*
X798220D01*
G01X801853Y300515D02*
X799748Y302620D01*
G01X801728Y305960D02*
Y304572D01*
G01X800568Y307120D02*
X801728Y305960D01*
G01X798220Y307120D02*
X800568D01*
G01X792482Y306335D02*
X789597D01*
G01X793267Y307120D02*
X792482Y306335D01*
G01X794720Y307120D02*
X793267D01*
G01X787015Y306335D02*
X789597D01*
G01X784351Y303671D02*
X787015Y306335D01*
G01X781198Y303671D02*
X784351D01*
G01X765018Y314495D02*
X763505Y316008D01*
G01X765018Y308791D02*
Y314495D01*
G01X763505Y316008D02*
X762329Y317184D01*
G01X762176Y306231D02*
X765018D01*
G01X760518Y307889D02*
X762176Y306231D01*
G01X760518Y310272D02*
Y307889D01*
G01X759866Y310924D02*
X760518Y310272D01*
G01X782840Y328180D02*
X782800Y328220D01*
G01X786560Y328180D02*
X782840D01*
G01X791520Y327000D02*
Y338394D01*
G01X789500Y327000D02*
X791520D01*
G01X788320Y328180D02*
X789500Y327000D01*
G01X786560Y328180D02*
X788320D01*
G54D12*
G01X6250Y-135162D02*
Y-152662D01*
G01X1228Y-135162D02*
X11272D01*
G01X20038Y-152662D02*
Y-135162D01*
G01Y-143620D02*
X21130Y-142162D01*
X22222Y-141287D01*
X23968Y-140996D01*
X25278Y-141287D01*
X26807Y-142454D01*
X27462Y-144204D01*
Y-152662D01*
G01X41250Y-140996D02*
Y-152662D01*
G01Y-136329D02*
X40813Y-136037D01*
Y-135454D01*
X41250Y-135162D01*
X41687Y-135454D01*
Y-136037D01*
X41250Y-136329D01*
G01X55475Y-150621D02*
X56567Y-151787D01*
X58095Y-152662D01*
X59405D01*
X60715Y-152079D01*
X61588Y-151204D01*
X62025Y-150038D01*
X61807Y-148287D01*
X60933Y-147412D01*
X57003Y-145662D01*
X56130Y-143620D01*
X56567Y-142162D01*
X57440Y-141287D01*
X58750Y-140996D01*
X60060Y-141287D01*
X61370Y-142162D01*
G01X90693Y-157037D02*
X92222Y-158204D01*
X93968Y-158495D01*
X95496Y-158204D01*
X96807Y-156746D01*
X97680Y-154704D01*
Y-140996D01*
G01Y-143329D02*
X96807Y-142162D01*
X95496Y-141287D01*
X93968Y-140996D01*
X92222Y-141579D01*
X91130Y-142745D01*
X90256Y-144787D01*
X89820Y-146829D01*
X90038Y-148579D01*
X90912Y-150621D01*
X92222Y-152079D01*
X93968Y-152662D01*
X95278Y-152370D01*
X96807Y-151204D01*
X97680Y-150038D01*
G01X107975Y-144787D02*
X114962D01*
X114307Y-142745D01*
X113215Y-141579D01*
X111687Y-140996D01*
X110158Y-141287D01*
X108848Y-142162D01*
X107975Y-144204D01*
X107538Y-145954D01*
Y-147704D01*
X107975Y-149454D01*
X109067Y-151204D01*
X110377Y-152370D01*
X111905Y-152662D01*
X113433Y-152079D01*
X114962Y-150329D01*
G01X125693Y-152662D02*
Y-140996D01*
G01Y-143329D02*
X126785Y-142162D01*
X127877Y-141287D01*
X129405Y-140996D01*
X130496Y-141287D01*
X131807Y-142162D01*
G01X142320Y-152662D02*
Y-135162D01*
G01Y-143912D02*
X143412Y-142162D01*
X144722Y-141287D01*
X146032Y-140996D01*
X147996Y-141579D01*
X149307Y-142745D01*
X150180Y-144787D01*
Y-147120D01*
X149743Y-149454D01*
X148870Y-151204D01*
X147342Y-152370D01*
X146032Y-152662D01*
X144722Y-152370D01*
X143412Y-151496D01*
X142320Y-150038D01*
G01X160475Y-144787D02*
X167462D01*
X166807Y-142745D01*
X165715Y-141579D01*
X164187Y-140996D01*
X162658Y-141287D01*
X161348Y-142162D01*
X160475Y-144204D01*
X160038Y-145954D01*
Y-147704D01*
X160475Y-149454D01*
X161567Y-151204D01*
X162877Y-152370D01*
X164405Y-152662D01*
X165933Y-152079D01*
X167462Y-150329D01*
G01X178193Y-152662D02*
Y-140996D01*
G01Y-143329D02*
X179285Y-142162D01*
X180377Y-141287D01*
X181905Y-140996D01*
X182996Y-141287D01*
X184307Y-142162D01*
G01X216250Y-140996D02*
Y-152662D01*
G01Y-136329D02*
X215813Y-136037D01*
Y-135454D01*
X216250Y-135162D01*
X216687Y-135454D01*
Y-136037D01*
X216250Y-136329D01*
G01X230475Y-150621D02*
X231567Y-151787D01*
X233095Y-152662D01*
X234405D01*
X235715Y-152079D01*
X236588Y-151204D01*
X237025Y-150038D01*
X236807Y-148287D01*
X235933Y-147412D01*
X232003Y-145662D01*
X231130Y-143620D01*
X231567Y-142162D01*
X232440Y-141287D01*
X233750Y-140996D01*
X235060Y-141287D01*
X236370Y-142162D01*
G01X265256Y-157037D02*
X266785Y-158204D01*
X268095Y-158495D01*
X269842Y-157912D01*
X271152Y-156454D01*
X271807Y-153828D01*
Y-140996D01*
G01Y-136329D02*
X271370Y-136037D01*
Y-135454D01*
X271807Y-135162D01*
X272243Y-135454D01*
Y-136037D01*
X271807Y-136329D01*
G01X282538Y-140996D02*
Y-149162D01*
X283412Y-151204D01*
X284722Y-152370D01*
X286250Y-152662D01*
X287778Y-152370D01*
X289088Y-151204D01*
X289962Y-149162D01*
G01Y-152662D02*
Y-140996D01*
G01X300475Y-150621D02*
X301567Y-151787D01*
X303095Y-152662D01*
X304405D01*
X305715Y-152079D01*
X306588Y-151204D01*
X307025Y-150038D01*
X306807Y-148287D01*
X305933Y-147412D01*
X302003Y-145662D01*
X301130Y-143620D01*
X301567Y-142162D01*
X302440Y-141287D01*
X303750Y-140996D01*
X305060Y-141287D01*
X306370Y-142162D01*
G01X321250Y-135162D02*
Y-152662D01*
G01X318193Y-140996D02*
X324307D01*
G01X354940Y-152662D02*
Y-137787D01*
X355377Y-136329D01*
X356250Y-135454D01*
X357560Y-135162D01*
X358870Y-135745D01*
X359525Y-137204D01*
G01X356905Y-142162D02*
X352538D01*
G01X373750Y-152662D02*
X372440Y-152370D01*
X371130Y-151204D01*
X370256Y-149162D01*
X369820Y-146829D01*
X370256Y-144495D01*
X371130Y-142454D01*
X372440Y-141287D01*
X373750Y-140996D01*
X375060Y-141287D01*
X376370Y-142454D01*
X377243Y-144495D01*
X377462Y-146829D01*
X377243Y-149162D01*
X376370Y-151204D01*
X375060Y-152370D01*
X373750Y-152662D01*
G01X388193D02*
Y-140996D01*
G01Y-143329D02*
X389285Y-142162D01*
X390377Y-141287D01*
X391905Y-140996D01*
X392996Y-141287D01*
X394307Y-142162D01*
G01X421665Y-157912D02*
X422975Y-158495D01*
X424722Y-157912D01*
X425813Y-156746D01*
X426687Y-155287D01*
X427996Y-150621D01*
X430835Y-140996D01*
G01X423848D02*
X427996Y-150621D01*
G01X443750Y-152662D02*
X442440Y-152370D01*
X441130Y-151204D01*
X440256Y-149162D01*
X439820Y-146829D01*
X440256Y-144495D01*
X441130Y-142454D01*
X442440Y-141287D01*
X443750Y-140996D01*
X445060Y-141287D01*
X446370Y-142454D01*
X447243Y-144495D01*
X447462Y-146829D01*
X447243Y-149162D01*
X446370Y-151204D01*
X445060Y-152370D01*
X443750Y-152662D01*
G01X457538Y-140996D02*
Y-149162D01*
X458412Y-151204D01*
X459722Y-152370D01*
X461250Y-152662D01*
X462778Y-152370D01*
X464088Y-151204D01*
X464962Y-149162D01*
G01Y-152662D02*
Y-140996D01*
G01X475693Y-152662D02*
Y-140996D01*
G01Y-143329D02*
X476785Y-142162D01*
X477877Y-141287D01*
X479405Y-140996D01*
X480496Y-141287D01*
X481807Y-142162D01*
G01X510693Y-152662D02*
Y-140996D01*
G01Y-143329D02*
X511785Y-142162D01*
X512877Y-141287D01*
X514405Y-140996D01*
X515496Y-141287D01*
X516807Y-142162D01*
G01X527975Y-144787D02*
X534962D01*
X534307Y-142745D01*
X533215Y-141579D01*
X531687Y-140996D01*
X530158Y-141287D01*
X528848Y-142162D01*
X527975Y-144204D01*
X527538Y-145954D01*
Y-147704D01*
X527975Y-149454D01*
X529067Y-151204D01*
X530377Y-152370D01*
X531905Y-152662D01*
X533433Y-152079D01*
X534962Y-150329D01*
G01X547440Y-152662D02*
Y-137787D01*
X547877Y-136329D01*
X548750Y-135454D01*
X550060Y-135162D01*
X551370Y-135745D01*
X552025Y-137204D01*
G01X549405Y-142162D02*
X545038D01*
G01X562975Y-144787D02*
X569962D01*
X569307Y-142745D01*
X568215Y-141579D01*
X566687Y-140996D01*
X565158Y-141287D01*
X563848Y-142162D01*
X562975Y-144204D01*
X562538Y-145954D01*
Y-147704D01*
X562975Y-149454D01*
X564067Y-151204D01*
X565377Y-152370D01*
X566905Y-152662D01*
X568433Y-152079D01*
X569962Y-150329D01*
G01X580693Y-152662D02*
Y-140996D01*
G01Y-143329D02*
X581785Y-142162D01*
X582877Y-141287D01*
X584405Y-140996D01*
X585496Y-141287D01*
X586807Y-142162D01*
G01X597975Y-144787D02*
X604962D01*
X604307Y-142745D01*
X603215Y-141579D01*
X601687Y-140996D01*
X600158Y-141287D01*
X598848Y-142162D01*
X597975Y-144204D01*
X597538Y-145954D01*
Y-147704D01*
X597975Y-149454D01*
X599067Y-151204D01*
X600377Y-152370D01*
X601905Y-152662D01*
X603433Y-152079D01*
X604962Y-150329D01*
G01X615038Y-152662D02*
Y-140996D01*
G01Y-143912D02*
X615912Y-142454D01*
X617222Y-141287D01*
X618968Y-140996D01*
X620496Y-141287D01*
X621807Y-142454D01*
X622462Y-144495D01*
Y-152662D01*
G01X639743Y-142454D02*
X638215Y-141287D01*
X636905Y-140996D01*
X635158Y-141579D01*
X633848Y-142745D01*
X632975Y-144787D01*
X632756Y-146829D01*
X632975Y-148871D01*
X633848Y-150621D01*
X635158Y-152079D01*
X636905Y-152662D01*
X638433Y-152079D01*
X639743Y-150912D01*
G01X650475Y-144787D02*
X657462D01*
X656807Y-142745D01*
X655715Y-141579D01*
X654187Y-140996D01*
X652658Y-141287D01*
X651348Y-142162D01*
X650475Y-144204D01*
X650038Y-145954D01*
Y-147704D01*
X650475Y-149454D01*
X651567Y-151204D01*
X652877Y-152370D01*
X654405Y-152662D01*
X655933Y-152079D01*
X657462Y-150329D01*
G01X688750Y-135162D02*
Y-152662D01*
G01X685693Y-140996D02*
X691807D01*
G01X706250Y-152662D02*
X704940Y-152370D01*
X703630Y-151204D01*
X702756Y-149162D01*
X702320Y-146829D01*
X702756Y-144495D01*
X703630Y-142454D01*
X704940Y-141287D01*
X706250Y-140996D01*
X707560Y-141287D01*
X708870Y-142454D01*
X709743Y-144495D01*
X709962Y-146829D01*
X709743Y-149162D01*
X708870Y-151204D01*
X707560Y-152370D01*
X706250Y-152662D01*
G01X739940D02*
Y-137787D01*
X740377Y-136329D01*
X741250Y-135454D01*
X742560Y-135162D01*
X743870Y-135745D01*
X744525Y-137204D01*
G01X741905Y-142162D02*
X737538D01*
G01X758750Y-140996D02*
Y-152662D01*
G01Y-136329D02*
X758313Y-136037D01*
Y-135454D01*
X758750Y-135162D01*
X759187Y-135454D01*
Y-136037D01*
X758750Y-136329D01*
G01X772538Y-152662D02*
Y-140996D01*
G01Y-143912D02*
X773412Y-142454D01*
X774722Y-141287D01*
X776468Y-140996D01*
X777996Y-141287D01*
X779307Y-142454D01*
X779962Y-144495D01*
Y-152662D01*
G01X797680Y-135162D02*
Y-152662D01*
G01Y-150038D02*
X796807Y-151496D01*
X795496Y-152370D01*
X793968Y-152662D01*
X792222Y-152079D01*
X790912Y-150621D01*
X790038Y-148871D01*
X789820Y-146829D01*
X790038Y-144787D01*
X790912Y-143037D01*
X792222Y-141579D01*
X793968Y-140996D01*
X795496Y-141287D01*
X796588Y-141871D01*
X797680Y-143037D01*
G01X828750Y-135162D02*
Y-152662D01*
G01X825693Y-140996D02*
X831807D01*
G01X842538Y-152662D02*
Y-135162D01*
G01Y-143620D02*
X843630Y-142162D01*
X844722Y-141287D01*
X846468Y-140996D01*
X847778Y-141287D01*
X849307Y-142454D01*
X849962Y-144204D01*
Y-152662D01*
G01X860475Y-144787D02*
X867462D01*
X866807Y-142745D01*
X865715Y-141579D01*
X864187Y-140996D01*
X862658Y-141287D01*
X861348Y-142162D01*
X860475Y-144204D01*
X860038Y-145954D01*
Y-147704D01*
X860475Y-149454D01*
X861567Y-151204D01*
X862877Y-152370D01*
X864405Y-152662D01*
X865933Y-152079D01*
X867462Y-150329D01*
G01X894165D02*
X895912Y-151787D01*
X897877Y-152662D01*
X899623D01*
X901370Y-151787D01*
X902680Y-150329D01*
X903335Y-148287D01*
X902898Y-146246D01*
X901807Y-144495D01*
X899842Y-143329D01*
X897222Y-142745D01*
X895693Y-141579D01*
X895038Y-139537D01*
X895475Y-137495D01*
X896567Y-136037D01*
X898095Y-135162D01*
X899623D01*
X901152Y-135745D01*
X902462Y-137204D01*
G01X920617Y-152662D02*
X911883D01*
Y-135162D01*
X920617D01*
G01X917123Y-143620D02*
X911883D01*
G01X951250Y-140996D02*
Y-152662D01*
G01Y-136329D02*
X950813Y-136037D01*
Y-135454D01*
X951250Y-135162D01*
X951687Y-135454D01*
Y-136037D01*
X951250Y-136329D01*
G01X962200Y-152662D02*
Y-140996D01*
G01Y-144204D02*
X962855Y-142745D01*
X963947Y-141579D01*
X965475Y-140996D01*
X967003Y-141579D01*
X968095Y-142745D01*
X968750Y-144204D01*
Y-152662D01*
G01Y-144204D02*
X969405Y-142745D01*
X970496Y-141579D01*
X972025Y-140996D01*
X973553Y-141579D01*
X974645Y-142745D01*
X975300Y-144495D01*
Y-152662D01*
G01X982320Y-158495D02*
Y-140996D01*
G01Y-143620D02*
X983412Y-142162D01*
X984503Y-141287D01*
X986250Y-140996D01*
X987778Y-141287D01*
X989307Y-142745D01*
X989962Y-144787D01*
X990180Y-146829D01*
X989962Y-148871D01*
X989307Y-150912D01*
X987996Y-152079D01*
X986250Y-152662D01*
X984722Y-152370D01*
X983193Y-151496D01*
X982320Y-150329D01*
G01X1000475Y-144787D02*
X1007462D01*
X1006807Y-142745D01*
X1005715Y-141579D01*
X1004187Y-140996D01*
X1002658Y-141287D01*
X1001348Y-142162D01*
X1000475Y-144204D01*
X1000038Y-145954D01*
Y-147704D01*
X1000475Y-149454D01*
X1001567Y-151204D01*
X1002877Y-152370D01*
X1004405Y-152662D01*
X1005933Y-152079D01*
X1007462Y-150329D01*
G01X1025180Y-135162D02*
Y-152662D01*
G01Y-150038D02*
X1024307Y-151496D01*
X1022996Y-152370D01*
X1021468Y-152662D01*
X1019722Y-152079D01*
X1018412Y-150621D01*
X1017538Y-148871D01*
X1017320Y-146829D01*
X1017538Y-144787D01*
X1018412Y-143037D01*
X1019722Y-141579D01*
X1021468Y-140996D01*
X1022996Y-141287D01*
X1024088Y-141871D01*
X1025180Y-143037D01*
G01X1042680Y-152662D02*
Y-140996D01*
G01Y-143037D02*
X1041807Y-141871D01*
X1040496Y-141287D01*
X1038968Y-140996D01*
X1037440Y-141579D01*
X1036130Y-142745D01*
X1035256Y-144495D01*
X1034820Y-146829D01*
X1035256Y-149162D01*
X1036130Y-150912D01*
X1037440Y-152079D01*
X1038968Y-152662D01*
X1040496Y-152370D01*
X1041807Y-151496D01*
X1042680Y-150329D01*
G01X1052538Y-152662D02*
Y-140996D01*
G01Y-143912D02*
X1053412Y-142454D01*
X1054722Y-141287D01*
X1056468Y-140996D01*
X1057996Y-141287D01*
X1059307Y-142454D01*
X1059962Y-144495D01*
Y-152662D01*
G01X1077243Y-142454D02*
X1075715Y-141287D01*
X1074405Y-140996D01*
X1072658Y-141579D01*
X1071348Y-142745D01*
X1070475Y-144787D01*
X1070256Y-146829D01*
X1070475Y-148871D01*
X1071348Y-150621D01*
X1072658Y-152079D01*
X1074405Y-152662D01*
X1075933Y-152079D01*
X1077243Y-150912D01*
G01X1087975Y-144787D02*
X1094962D01*
X1094307Y-142745D01*
X1093215Y-141579D01*
X1091687Y-140996D01*
X1090158Y-141287D01*
X1088848Y-142162D01*
X1087975Y-144204D01*
X1087538Y-145954D01*
Y-147704D01*
X1087975Y-149454D01*
X1089067Y-151204D01*
X1090377Y-152370D01*
X1091905Y-152662D01*
X1093433Y-152079D01*
X1094962Y-150329D01*
G01X1126250Y-135162D02*
Y-152662D01*
G01X1123193Y-140996D02*
X1129307D01*
G01X1140693Y-152662D02*
Y-140996D01*
G01Y-143329D02*
X1141785Y-142162D01*
X1142877Y-141287D01*
X1144405Y-140996D01*
X1145496Y-141287D01*
X1146807Y-142162D01*
G01X1165180Y-152662D02*
Y-140996D01*
G01Y-143037D02*
X1164307Y-141871D01*
X1162996Y-141287D01*
X1161468Y-140996D01*
X1159940Y-141579D01*
X1158630Y-142745D01*
X1157756Y-144495D01*
X1157320Y-146829D01*
X1157756Y-149162D01*
X1158630Y-150912D01*
X1159940Y-152079D01*
X1161468Y-152662D01*
X1162996Y-152370D01*
X1164307Y-151496D01*
X1165180Y-150329D01*
G01X1182243Y-142454D02*
X1180715Y-141287D01*
X1179405Y-140996D01*
X1177658Y-141579D01*
X1176348Y-142745D01*
X1175475Y-144787D01*
X1175256Y-146829D01*
X1175475Y-148871D01*
X1176348Y-150621D01*
X1177658Y-152079D01*
X1179405Y-152662D01*
X1180933Y-152079D01*
X1182243Y-150912D01*
G01X1192975Y-144787D02*
X1199962D01*
X1199307Y-142745D01*
X1198215Y-141579D01*
X1196687Y-140996D01*
X1195158Y-141287D01*
X1193848Y-142162D01*
X1192975Y-144204D01*
X1192538Y-145954D01*
Y-147704D01*
X1192975Y-149454D01*
X1194067Y-151204D01*
X1195377Y-152370D01*
X1196905Y-152662D01*
X1198433Y-152079D01*
X1199962Y-150329D01*
G01X1210475Y-150621D02*
X1211567Y-151787D01*
X1213095Y-152662D01*
X1214405D01*
X1215715Y-152079D01*
X1216588Y-151204D01*
X1217025Y-150038D01*
X1216807Y-148287D01*
X1215933Y-147412D01*
X1212003Y-145662D01*
X1211130Y-143620D01*
X1211567Y-142162D01*
X1212440Y-141287D01*
X1213750Y-140996D01*
X1215060Y-141287D01*
X1216370Y-142162D01*
G01X1248750Y-140996D02*
Y-152662D01*
G01Y-136329D02*
X1248313Y-136037D01*
Y-135454D01*
X1248750Y-135162D01*
X1249187Y-135454D01*
Y-136037D01*
X1248750Y-136329D01*
G01X1262538Y-152662D02*
Y-140996D01*
G01Y-143912D02*
X1263412Y-142454D01*
X1264722Y-141287D01*
X1266468Y-140996D01*
X1267996Y-141287D01*
X1269307Y-142454D01*
X1269962Y-144495D01*
Y-152662D01*
G01X1301250D02*
Y-135162D01*
G01X1322680Y-152662D02*
Y-140996D01*
G01Y-143037D02*
X1321807Y-141871D01*
X1320496Y-141287D01*
X1318968Y-140996D01*
X1317440Y-141579D01*
X1316130Y-142745D01*
X1315256Y-144495D01*
X1314820Y-146829D01*
X1315256Y-149162D01*
X1316130Y-150912D01*
X1317440Y-152079D01*
X1318968Y-152662D01*
X1320496Y-152370D01*
X1321807Y-151496D01*
X1322680Y-150329D01*
G01X1331665Y-157912D02*
X1332975Y-158495D01*
X1334722Y-157912D01*
X1335813Y-156746D01*
X1336687Y-155287D01*
X1337996Y-150621D01*
X1340835Y-140996D01*
G01X1333848D02*
X1337996Y-150621D01*
G01X1350475Y-144787D02*
X1357462D01*
X1356807Y-142745D01*
X1355715Y-141579D01*
X1354187Y-140996D01*
X1352658Y-141287D01*
X1351348Y-142162D01*
X1350475Y-144204D01*
X1350038Y-145954D01*
Y-147704D01*
X1350475Y-149454D01*
X1351567Y-151204D01*
X1352877Y-152370D01*
X1354405Y-152662D01*
X1355933Y-152079D01*
X1357462Y-150329D01*
G01X1368193Y-152662D02*
Y-140996D01*
G01Y-143329D02*
X1369285Y-142162D01*
X1370377Y-141287D01*
X1371905Y-140996D01*
X1372996Y-141287D01*
X1374307Y-142162D01*
G01X1401883Y-135162D02*
Y-152662D01*
X1410617D01*
G01X1423750D02*
Y-135162D01*
X1421130Y-138662D01*
G01Y-152662D02*
X1426370D01*
G01X1441250Y-153245D02*
X1440813Y-152954D01*
Y-152370D01*
X1441250Y-152079D01*
X1441687Y-152370D01*
Y-152954D01*
X1441250Y-153245D01*
G01X879036Y548599D02*
X880783Y547141D01*
X882748Y546266D01*
X884494D01*
X886241Y547141D01*
X887551Y548599D01*
X888206Y550641D01*
X887769Y552682D01*
X886678Y554433D01*
X884713Y555599D01*
X882093Y556183D01*
X880564Y557349D01*
X879909Y559391D01*
X880346Y561433D01*
X881438Y562891D01*
X882966Y563766D01*
X884494D01*
X886023Y563183D01*
X887333Y561724D01*
G01X905488Y546266D02*
X896754D01*
Y563766D01*
X905488D01*
G01X901994Y555308D02*
X896754D01*
G01X933501Y563766D02*
X938741D01*
G01X936121D02*
Y546266D01*
G01X933501D02*
X938741D01*
G01X947944D02*
Y563766D01*
X953621Y549183D01*
X959298Y563766D01*
Y546266D01*
G01X966754D02*
Y563766D01*
X971994D01*
X973741Y562891D01*
X975051Y560849D01*
X975488Y558516D01*
X975051Y556183D01*
X973959Y554433D01*
X971994Y553557D01*
X966754D01*
G01X992988Y546266D02*
X984254D01*
Y563766D01*
X992988D01*
G01X989494Y555308D02*
X984254D01*
G01X1001318Y546266D02*
Y563766D01*
X1005684D01*
X1007431Y562891D01*
X1008741Y561724D01*
X1009833Y559975D01*
X1010706Y557932D01*
X1010924Y555016D01*
X1010706Y552099D01*
X1009833Y550057D01*
X1008741Y548307D01*
X1007431Y547141D01*
X1005684Y546266D01*
X1001318D01*
G01X1018162D02*
X1023621Y563766D01*
X1029080Y546266D01*
G01X1027114Y552391D02*
X1020127D01*
G01X1036099Y546266D02*
Y563766D01*
X1046143Y546266D01*
Y563766D01*
G01X1063424Y562307D02*
X1062114Y563183D01*
X1060586Y563766D01*
X1058839D01*
X1056874Y562891D01*
X1055346Y561433D01*
X1054254Y559682D01*
X1053381Y556766D01*
X1053162Y554141D01*
X1053599Y551516D01*
X1054254Y549766D01*
X1055564Y548016D01*
X1057093Y546849D01*
X1058621Y546266D01*
X1060149D01*
X1061678Y546849D01*
X1062988Y547724D01*
X1064080Y548890D01*
G01X1080488Y546266D02*
X1071754D01*
Y563766D01*
X1080488D01*
G01X1076994Y555308D02*
X1071754D01*
G01X1111121Y563766D02*
Y546266D01*
G01X1106099Y563766D02*
X1116143D01*
G01X1123162Y546266D02*
X1128621Y563766D01*
X1134080Y546266D01*
G01X1132114Y552391D02*
X1125127D01*
G01X1147867Y555599D02*
X1148741Y556474D01*
X1149396Y557932D01*
X1149833Y559975D01*
X1149396Y561724D01*
X1148523Y562891D01*
X1146994Y563766D01*
X1141099D01*
Y546266D01*
X1148304D01*
X1149833Y547432D01*
X1150706Y549183D01*
X1151143Y551224D01*
X1150706Y553266D01*
X1149396Y555016D01*
X1147867Y555599D01*
X1141099D01*
G01X1159254Y563766D02*
Y546266D01*
X1167988D01*
G01X1185488D02*
X1176754D01*
Y563766D01*
X1185488D01*
G01X1181994Y555308D02*
X1176754D01*
G01X1198621Y545683D02*
X1198184Y545974D01*
Y546558D01*
X1198621Y546849D01*
X1199058Y546558D01*
Y545974D01*
X1198621Y545683D01*
G01Y553557D02*
X1198184Y553849D01*
Y554433D01*
X1198621Y554724D01*
X1199058Y554433D01*
Y553849D01*
X1198621Y553557D01*
G01X1229254Y563766D02*
Y546266D01*
X1237988D01*
G01X1251121D02*
Y563766D01*
X1248501Y560266D01*
G01Y546266D02*
X1253741D01*
G01X933518Y479590D02*
X934827Y478132D01*
X936356Y477258D01*
X938321Y476966D01*
X940286Y477549D01*
X941814Y478716D01*
X942906Y480757D01*
X943124Y483091D01*
X942688Y485424D01*
X941596Y486883D01*
X940067Y488049D01*
X938539Y488341D01*
X937011Y488049D01*
X935046Y486883D01*
X935701Y494466D01*
X941596D01*
G01X955821D02*
X954074Y493883D01*
X952764Y492424D01*
X951891Y490675D01*
X951236Y488341D01*
X951018Y485716D01*
X951236Y483091D01*
X951891Y480757D01*
X952764Y479007D01*
X954074Y477549D01*
X955821Y476966D01*
X957567Y477549D01*
X958878Y479007D01*
X959751Y480757D01*
X960406Y483091D01*
X960624Y485716D01*
X960406Y488341D01*
X959751Y490675D01*
X958878Y492424D01*
X957567Y493883D01*
X955821Y494466D01*
G01X973321Y476383D02*
X972884Y476674D01*
Y477258D01*
X973321Y477549D01*
X973758Y477258D01*
Y476674D01*
X973321Y476383D01*
G01X990821Y494466D02*
X989074Y493883D01*
X987764Y492424D01*
X986891Y490675D01*
X986236Y488341D01*
X986018Y485716D01*
X986236Y483091D01*
X986891Y480757D01*
X987764Y479007D01*
X989074Y477549D01*
X990821Y476966D01*
X992567Y477549D01*
X993878Y479007D01*
X994751Y480757D01*
X995406Y483091D01*
X995624Y485716D01*
X995406Y488341D01*
X994751Y490675D01*
X993878Y492424D01*
X992567Y493883D01*
X990821Y494466D01*
G01X900701Y529116D02*
X905941D01*
G01X903321D02*
Y511616D01*
G01X900701D02*
X905941D01*
G01X915144D02*
Y529116D01*
X920821Y514533D01*
X926498Y529116D01*
Y511616D01*
G01X933954D02*
Y529116D01*
X939194D01*
X940941Y528241D01*
X942251Y526199D01*
X942688Y523866D01*
X942251Y521533D01*
X941159Y519783D01*
X939194Y518907D01*
X933954D01*
G01X954729Y505783D02*
X952546Y508699D01*
X951454Y511616D01*
Y523282D01*
X952546Y526199D01*
X954729Y529116D01*
G01X973321Y511616D02*
X971574Y511908D01*
X970046Y513074D01*
X968736Y514824D01*
X967862Y516866D01*
X967426Y519199D01*
Y521533D01*
X967862Y523866D01*
X968736Y525908D01*
X970046Y527657D01*
X971574Y528824D01*
X973321Y529116D01*
X975067Y528824D01*
X976596Y527657D01*
X977906Y525908D01*
X978780Y523866D01*
X979216Y521533D01*
Y519199D01*
X978780Y516866D01*
X977906Y514824D01*
X976596Y513074D01*
X975067Y511908D01*
X973321Y511616D01*
G01X987109D02*
Y529116D01*
G01Y520658D02*
X988201Y522116D01*
X989293Y522991D01*
X991039Y523282D01*
X992349Y522991D01*
X993878Y521824D01*
X994533Y520074D01*
Y511616D01*
G01X1001771D02*
Y523282D01*
G01Y520074D02*
X1002426Y521533D01*
X1003518Y522699D01*
X1005046Y523282D01*
X1006574Y522699D01*
X1007666Y521533D01*
X1008321Y520074D01*
Y511616D01*
G01Y520074D02*
X1008976Y521533D01*
X1010067Y522699D01*
X1011596Y523282D01*
X1013124Y522699D01*
X1014216Y521533D01*
X1014871Y519783D01*
Y511616D01*
G01X1026913Y505783D02*
X1029096Y508699D01*
X1030188Y511616D01*
Y523282D01*
X1029096Y526199D01*
X1026913Y529116D01*
G01X1071771D02*
X1074827Y511616D01*
X1078321Y529116D01*
X1081814Y511616D01*
X1084871Y529116D01*
G01X1093201D02*
X1098441D01*
G01X1095821D02*
Y511616D01*
G01X1093201D02*
X1098441D01*
G01X1108518D02*
Y529116D01*
X1112884D01*
X1114631Y528241D01*
X1115941Y527074D01*
X1117033Y525325D01*
X1117906Y523282D01*
X1118124Y520366D01*
X1117906Y517449D01*
X1117033Y515407D01*
X1115941Y513657D01*
X1114631Y512491D01*
X1112884Y511616D01*
X1108518D01*
G01X1130821Y529116D02*
Y511616D01*
G01X1125799Y529116D02*
X1135843D01*
G01X1143736Y511616D02*
Y529116D01*
G01X1152906D02*
Y511616D01*
G01Y520366D02*
X1143736D01*
G01X1164729Y505783D02*
X1162546Y508699D01*
X1161454Y511616D01*
Y523282D01*
X1162546Y526199D01*
X1164729Y529116D01*
G01X1176771Y511616D02*
Y523282D01*
G01Y520074D02*
X1177426Y521533D01*
X1178518Y522699D01*
X1180046Y523282D01*
X1181574Y522699D01*
X1182666Y521533D01*
X1183321Y520074D01*
Y511616D01*
G01Y520074D02*
X1183976Y521533D01*
X1185067Y522699D01*
X1186596Y523282D01*
X1188124Y522699D01*
X1189216Y521533D01*
X1189871Y519783D01*
Y511616D01*
G01X1200821Y523282D02*
Y511616D01*
G01Y527949D02*
X1200384Y528241D01*
Y528824D01*
X1200821Y529116D01*
X1201258Y528824D01*
Y528241D01*
X1200821Y527949D01*
G01X1218321Y511616D02*
Y529116D01*
G01X1232546Y513657D02*
X1233638Y512491D01*
X1235166Y511616D01*
X1236476D01*
X1237786Y512199D01*
X1238659Y513074D01*
X1239096Y514240D01*
X1238878Y515991D01*
X1238004Y516866D01*
X1234074Y518616D01*
X1233201Y520658D01*
X1233638Y522116D01*
X1234511Y522991D01*
X1235821Y523282D01*
X1237131Y522991D01*
X1238441Y522116D01*
G01X1254413Y505783D02*
X1256596Y508699D01*
X1257688Y511616D01*
Y523282D01*
X1256596Y526199D01*
X1254413Y529116D01*
G01X1143518Y479590D02*
X1144827Y478132D01*
X1146356Y477258D01*
X1148321Y476966D01*
X1150286Y477549D01*
X1151814Y478716D01*
X1152906Y480757D01*
X1153124Y483091D01*
X1152688Y485424D01*
X1151596Y486883D01*
X1150067Y488049D01*
X1148539Y488341D01*
X1147011Y488049D01*
X1145046Y486883D01*
X1145701Y494466D01*
X1151596D01*
G01X1165821Y476383D02*
X1165384Y476674D01*
Y477258D01*
X1165821Y477549D01*
X1166258Y477258D01*
Y476674D01*
X1165821Y476383D01*
G01X1183321Y494466D02*
X1181574Y493883D01*
X1180264Y492424D01*
X1179391Y490675D01*
X1178736Y488341D01*
X1178518Y485716D01*
X1178736Y483091D01*
X1179391Y480757D01*
X1180264Y479007D01*
X1181574Y477549D01*
X1183321Y476966D01*
X1185067Y477549D01*
X1186378Y479007D01*
X1187251Y480757D01*
X1187906Y483091D01*
X1188124Y485716D01*
X1187906Y488341D01*
X1187251Y490675D01*
X1186378Y492424D01*
X1185067Y493883D01*
X1183321Y494466D01*
G01X1318736Y479299D02*
X1320483Y477841D01*
X1322448Y476966D01*
X1324194D01*
X1325941Y477841D01*
X1327251Y479299D01*
X1327906Y481341D01*
X1327469Y483382D01*
X1326378Y485133D01*
X1324413Y486299D01*
X1321793Y486883D01*
X1320264Y488049D01*
X1319609Y490091D01*
X1320046Y492133D01*
X1321138Y493591D01*
X1322666Y494466D01*
X1324194D01*
X1325723Y493883D01*
X1327033Y492424D01*
G01X1345188Y476966D02*
X1336454D01*
Y494466D01*
X1345188D01*
G01X1341694Y486008D02*
X1336454D01*
G01X1305821Y529116D02*
Y511616D01*
G01X1300799Y529116D02*
X1310843D01*
G01X1323321Y511616D02*
Y519491D01*
X1318954Y529116D01*
G01X1327688D02*
X1323321Y519491D01*
G01X1336454Y511616D02*
Y529116D01*
X1341694D01*
X1343441Y528241D01*
X1344751Y526199D01*
X1345188Y523866D01*
X1344751Y521533D01*
X1343659Y519783D01*
X1341694Y518907D01*
X1336454D01*
G01X1362688Y511616D02*
X1353954D01*
Y529116D01*
X1362688D01*
G01X1359194Y520658D02*
X1353954D01*
G01X1406454Y511616D02*
Y529116D01*
X1411913D01*
X1413659Y528241D01*
X1414751Y527074D01*
X1415188Y524741D01*
X1414751Y522407D01*
X1413441Y520949D01*
X1411913Y520074D01*
X1406454D01*
G01X1411913D02*
X1415188Y511616D01*
G01X1425046Y519491D02*
X1432033D01*
X1431378Y521533D01*
X1430286Y522699D01*
X1428758Y523282D01*
X1427229Y522991D01*
X1425919Y522116D01*
X1425046Y520074D01*
X1424609Y518324D01*
Y516574D01*
X1425046Y514824D01*
X1426138Y513074D01*
X1427448Y511908D01*
X1428976Y511616D01*
X1430504Y512199D01*
X1432033Y513949D01*
G01X1444511Y511616D02*
Y526491D01*
X1444948Y527949D01*
X1445821Y528824D01*
X1447131Y529116D01*
X1448441Y528533D01*
X1449096Y527074D01*
G01X1446476Y522116D02*
X1442109D01*
G01X1463321Y511033D02*
X1462884Y511324D01*
Y511908D01*
X1463321Y512199D01*
X1463758Y511908D01*
Y511324D01*
X1463321Y511033D01*
G01X1493954Y511616D02*
Y529116D01*
X1499194D01*
X1500941Y528241D01*
X1502251Y526199D01*
X1502688Y523866D01*
X1502251Y521533D01*
X1501159Y519783D01*
X1499194Y518907D01*
X1493954D01*
G01X1515821Y511616D02*
Y529116D01*
G01X1537251Y511616D02*
Y523282D01*
G01Y521241D02*
X1536378Y522407D01*
X1535067Y522991D01*
X1533539Y523282D01*
X1532011Y522699D01*
X1530701Y521533D01*
X1529827Y519783D01*
X1529391Y517449D01*
X1529827Y515116D01*
X1530701Y513366D01*
X1532011Y512199D01*
X1533539Y511616D01*
X1535067Y511908D01*
X1536378Y512782D01*
X1537251Y513949D01*
G01X1547109Y511616D02*
Y523282D01*
G01Y520366D02*
X1547983Y521824D01*
X1549293Y522991D01*
X1551039Y523282D01*
X1552567Y522991D01*
X1553878Y521824D01*
X1554533Y519783D01*
Y511616D01*
G01X1565046Y519491D02*
X1572033D01*
X1571378Y521533D01*
X1570286Y522699D01*
X1568758Y523282D01*
X1567229Y522991D01*
X1565919Y522116D01*
X1565046Y520074D01*
X1564609Y518324D01*
Y516574D01*
X1565046Y514824D01*
X1566138Y513074D01*
X1567448Y511908D01*
X1568976Y511616D01*
X1570504Y512199D01*
X1572033Y513949D01*
G01X1476454Y494466D02*
Y476966D01*
X1485188D01*
G01X1494173Y491549D02*
X1495483Y493299D01*
X1497011Y494174D01*
X1498758Y494466D01*
X1500941Y493883D01*
X1502469Y492424D01*
X1502906Y490675D01*
X1502688Y488924D01*
X1501814Y487466D01*
X1497448Y484549D01*
X1495483Y482508D01*
X1494173Y479590D01*
X1493736Y476966D01*
X1502906D01*
G01X1686121Y488632D02*
Y476966D01*
G01Y493299D02*
X1685684Y493591D01*
Y494174D01*
X1686121Y494466D01*
X1686558Y494174D01*
Y493591D01*
X1686121Y493299D01*
G01X1700346Y479007D02*
X1701438Y477841D01*
X1702966Y476966D01*
X1704276D01*
X1705586Y477549D01*
X1706459Y478424D01*
X1706896Y479590D01*
X1706678Y481341D01*
X1705804Y482216D01*
X1701874Y483966D01*
X1701001Y486008D01*
X1701438Y487466D01*
X1702311Y488341D01*
X1703621Y488632D01*
X1704931Y488341D01*
X1706241Y487466D01*
G01X1733599Y476966D02*
Y494466D01*
X1743643Y476966D01*
Y494466D01*
G01X1756121Y476966D02*
X1754374Y477258D01*
X1752846Y478424D01*
X1751536Y480174D01*
X1750662Y482216D01*
X1750226Y484549D01*
Y486883D01*
X1750662Y489216D01*
X1751536Y491258D01*
X1752846Y493007D01*
X1754374Y494174D01*
X1756121Y494466D01*
X1757867Y494174D01*
X1759396Y493007D01*
X1760706Y491258D01*
X1761580Y489216D01*
X1762016Y486883D01*
Y484549D01*
X1761580Y482216D01*
X1760706Y480174D01*
X1759396Y478424D01*
X1757867Y477258D01*
X1756121Y476966D01*
G01X1773621Y494466D02*
Y476966D01*
G01X1768599Y494466D02*
X1778643D01*
G01X1804909Y488632D02*
Y480466D01*
X1805783Y478424D01*
X1807093Y477258D01*
X1808621Y476966D01*
X1810149Y477258D01*
X1811459Y478424D01*
X1812333Y480466D01*
G01Y476966D02*
Y488632D01*
G01X1822846Y479007D02*
X1823938Y477841D01*
X1825466Y476966D01*
X1826776D01*
X1828086Y477549D01*
X1828959Y478424D01*
X1829396Y479590D01*
X1829178Y481341D01*
X1828304Y482216D01*
X1824374Y483966D01*
X1823501Y486008D01*
X1823938Y487466D01*
X1824811Y488341D01*
X1826121Y488632D01*
X1827431Y488341D01*
X1828741Y487466D01*
G01X1840346Y484841D02*
X1847333D01*
X1846678Y486883D01*
X1845586Y488049D01*
X1844058Y488632D01*
X1842529Y488341D01*
X1841219Y487466D01*
X1840346Y485424D01*
X1839909Y483674D01*
Y481924D01*
X1840346Y480174D01*
X1841438Y478424D01*
X1842748Y477258D01*
X1844276Y476966D01*
X1845804Y477549D01*
X1847333Y479299D01*
G01X1865051Y494466D02*
Y476966D01*
G01Y479590D02*
X1864178Y478132D01*
X1862867Y477258D01*
X1861339Y476966D01*
X1859593Y477549D01*
X1858283Y479007D01*
X1857409Y480757D01*
X1857191Y482799D01*
X1857409Y484841D01*
X1858283Y486591D01*
X1859593Y488049D01*
X1861339Y488632D01*
X1862867Y488341D01*
X1863959Y487757D01*
X1865051Y486591D01*
G01X1611318Y511033D02*
X1620924Y523866D01*
G01X1616121Y526199D02*
Y508699D01*
G01X1620924Y511033D02*
X1611318Y523866D01*
G01X1609571Y517449D02*
X1622671D01*
G01X1648283D02*
X1653959D01*
G01X1681318Y511616D02*
Y529116D01*
X1685684D01*
X1687431Y528241D01*
X1688741Y527074D01*
X1689833Y525325D01*
X1690706Y523282D01*
X1690924Y520366D01*
X1690706Y517449D01*
X1689833Y515407D01*
X1688741Y513657D01*
X1687431Y512491D01*
X1685684Y511616D01*
X1681318D01*
G01X1700346Y519491D02*
X1707333D01*
X1706678Y521533D01*
X1705586Y522699D01*
X1704058Y523282D01*
X1702529Y522991D01*
X1701219Y522116D01*
X1700346Y520074D01*
X1699909Y518324D01*
Y516574D01*
X1700346Y514824D01*
X1701438Y513074D01*
X1702748Y511908D01*
X1704276Y511616D01*
X1705804Y512199D01*
X1707333Y513949D01*
G01X1717409Y511616D02*
Y523282D01*
G01Y520366D02*
X1718283Y521824D01*
X1719593Y522991D01*
X1721339Y523282D01*
X1722867Y522991D01*
X1724178Y521824D01*
X1724833Y519783D01*
Y511616D01*
G01X1738621D02*
X1737311Y511908D01*
X1736001Y513074D01*
X1735127Y515116D01*
X1734691Y517449D01*
X1735127Y519783D01*
X1736001Y521824D01*
X1737311Y522991D01*
X1738621Y523282D01*
X1739931Y522991D01*
X1741241Y521824D01*
X1742114Y519783D01*
X1742333Y517449D01*
X1742114Y515116D01*
X1741241Y513074D01*
X1739931Y511908D01*
X1738621Y511616D01*
G01X1756121Y529116D02*
Y511616D01*
G01X1753064Y523282D02*
X1759178D01*
G01X1770346Y519491D02*
X1777333D01*
X1776678Y521533D01*
X1775586Y522699D01*
X1774058Y523282D01*
X1772529Y522991D01*
X1771219Y522116D01*
X1770346Y520074D01*
X1769909Y518324D01*
Y516574D01*
X1770346Y514824D01*
X1771438Y513074D01*
X1772748Y511908D01*
X1774276Y511616D01*
X1775804Y512199D01*
X1777333Y513949D01*
G01X1787846Y513657D02*
X1788938Y512491D01*
X1790466Y511616D01*
X1791776D01*
X1793086Y512199D01*
X1793959Y513074D01*
X1794396Y514240D01*
X1794178Y515991D01*
X1793304Y516866D01*
X1789374Y518616D01*
X1788501Y520658D01*
X1788938Y522116D01*
X1789811Y522991D01*
X1791121Y523282D01*
X1792431Y522991D01*
X1793741Y522116D01*
G01X1826121Y529116D02*
Y511616D01*
G01X1823064Y523282D02*
X1829178D01*
G01X1839909Y511616D02*
Y529116D01*
G01Y520658D02*
X1841001Y522116D01*
X1842093Y522991D01*
X1843839Y523282D01*
X1845149Y522991D01*
X1846678Y521824D01*
X1847333Y520074D01*
Y511616D01*
G01X1865051D02*
Y523282D01*
G01Y521241D02*
X1864178Y522407D01*
X1862867Y522991D01*
X1861339Y523282D01*
X1859811Y522699D01*
X1858501Y521533D01*
X1857627Y519783D01*
X1857191Y517449D01*
X1857627Y515116D01*
X1858501Y513366D01*
X1859811Y512199D01*
X1861339Y511616D01*
X1862867Y511908D01*
X1864178Y512782D01*
X1865051Y513949D01*
G01X1878621Y529116D02*
Y511616D01*
G01X1875564Y523282D02*
X1881678D01*
G01X1913621Y529116D02*
Y511616D01*
G01X1910564Y523282D02*
X1916678D01*
G01X1927409Y511616D02*
Y529116D01*
G01Y520658D02*
X1928501Y522116D01*
X1929593Y522991D01*
X1931339Y523282D01*
X1932649Y522991D01*
X1934178Y521824D01*
X1934833Y520074D01*
Y511616D01*
G01X1948621Y523282D02*
Y511616D01*
G01Y527949D02*
X1948184Y528241D01*
Y528824D01*
X1948621Y529116D01*
X1949058Y528824D01*
Y528241D01*
X1948621Y527949D01*
G01X1962846Y513657D02*
X1963938Y512491D01*
X1965466Y511616D01*
X1966776D01*
X1968086Y512199D01*
X1968959Y513074D01*
X1969396Y514240D01*
X1969178Y515991D01*
X1968304Y516866D01*
X1964374Y518616D01*
X1963501Y520658D01*
X1963938Y522116D01*
X1964811Y522991D01*
X1966121Y523282D01*
X1967431Y522991D01*
X1968741Y522116D01*
G01X1998501Y529116D02*
X2003741D01*
G01X2001121D02*
Y511616D01*
G01X1998501D02*
X2003741D01*
G01X2012071D02*
Y523282D01*
G01Y520074D02*
X2012726Y521533D01*
X2013818Y522699D01*
X2015346Y523282D01*
X2016874Y522699D01*
X2017966Y521533D01*
X2018621Y520074D01*
Y511616D01*
G01Y520074D02*
X2019276Y521533D01*
X2020367Y522699D01*
X2021896Y523282D01*
X2023424Y522699D01*
X2024516Y521533D01*
X2025171Y519783D01*
Y511616D01*
G01X2032191Y505783D02*
Y523282D01*
G01Y520658D02*
X2033283Y522116D01*
X2034374Y522991D01*
X2036121Y523282D01*
X2037649Y522991D01*
X2039178Y521533D01*
X2039833Y519491D01*
X2040051Y517449D01*
X2039833Y515407D01*
X2039178Y513366D01*
X2037867Y512199D01*
X2036121Y511616D01*
X2034593Y511908D01*
X2033064Y512782D01*
X2032191Y513949D01*
G01X2050346Y519491D02*
X2057333D01*
X2056678Y521533D01*
X2055586Y522699D01*
X2054058Y523282D01*
X2052529Y522991D01*
X2051219Y522116D01*
X2050346Y520074D01*
X2049909Y518324D01*
Y516574D01*
X2050346Y514824D01*
X2051438Y513074D01*
X2052748Y511908D01*
X2054276Y511616D01*
X2055804Y512199D01*
X2057333Y513949D01*
G01X2075051Y529116D02*
Y511616D01*
G01Y514240D02*
X2074178Y512782D01*
X2072867Y511908D01*
X2071339Y511616D01*
X2069593Y512199D01*
X2068283Y513657D01*
X2067409Y515407D01*
X2067191Y517449D01*
X2067409Y519491D01*
X2068283Y521241D01*
X2069593Y522699D01*
X2071339Y523282D01*
X2072867Y522991D01*
X2073959Y522407D01*
X2075051Y521241D01*
G01X2092551Y511616D02*
Y523282D01*
G01Y521241D02*
X2091678Y522407D01*
X2090367Y522991D01*
X2088839Y523282D01*
X2087311Y522699D01*
X2086001Y521533D01*
X2085127Y519783D01*
X2084691Y517449D01*
X2085127Y515116D01*
X2086001Y513366D01*
X2087311Y512199D01*
X2088839Y511616D01*
X2090367Y511908D01*
X2091678Y512782D01*
X2092551Y513949D01*
G01X2102409Y511616D02*
Y523282D01*
G01Y520366D02*
X2103283Y521824D01*
X2104593Y522991D01*
X2106339Y523282D01*
X2107867Y522991D01*
X2109178Y521824D01*
X2109833Y519783D01*
Y511616D01*
G01X2127114Y521824D02*
X2125586Y522991D01*
X2124276Y523282D01*
X2122529Y522699D01*
X2121219Y521533D01*
X2120346Y519491D01*
X2120127Y517449D01*
X2120346Y515407D01*
X2121219Y513657D01*
X2122529Y512199D01*
X2124276Y511616D01*
X2125804Y512199D01*
X2127114Y513366D01*
G01X2137846Y519491D02*
X2144833D01*
X2144178Y521533D01*
X2143086Y522699D01*
X2141558Y523282D01*
X2140029Y522991D01*
X2138719Y522116D01*
X2137846Y520074D01*
X2137409Y518324D01*
Y516574D01*
X2137846Y514824D01*
X2138938Y513074D01*
X2140248Y511908D01*
X2141776Y511616D01*
X2143304Y512199D01*
X2144833Y513949D01*
G01X20103Y-86244D02*
G03I-4291J0D01*
G01X0Y-87362D02*
G03X15000Y-102362I15000J0D01*
G01X0Y-11811D02*
Y-87362D01*
G01X3937Y-7874D02*
G03X0Y-11811I0J-3937D01*
G01X15748Y-7874D02*
X3937D01*
G01X0Y7874D02*
G03X7874Y0I7874J0D01*
G01X818897D02*
X7874D01*
G01X0Y7874D02*
Y562992D01*
G01X7874Y570866D02*
G03X0Y562992I0J-7874D01*
G01X7874Y570866D02*
X326781D01*
G01X312004Y-102362D02*
X15000D01*
G01X46456Y0D02*
G03Y-7874I0J-3937D01*
G01X15748D02*
G03Y0I0J3937D01*
G01X287400Y-7874D02*
X46456D01*
G01X40452Y499724D02*
G03I-3051J0D01*
G01X41535Y535157D02*
G03I-4134J0D01*
G01X44685Y517441D02*
G03I-7284J0D01*
G01X121082Y39055D02*
G03I-5019J0D01*
G01X120807Y14567D02*
G03I-4744J0D01*
G01X319878Y-102362D02*
G03X312004I-3937J0D01*
G01X811771D02*
X319878D01*
G01X326770Y0D02*
G03Y-7874I0J-3937D01*
G01X287400D02*
G03Y0I0J3937D01*
G01X302165Y531496D02*
G03I-6890J0D01*
G01X597707Y-7874D02*
X326770D01*
G01X379921Y156220D02*
G03I-5906J0D01*
G01X342529Y530315D02*
G03X334655I-3937J0D01*
G01X342529Y520720D02*
G03X352474Y509057I11811J0D01*
G01X334655Y520720D02*
G03X351230Y501282I19685J0D01*
G01X384484Y503937D02*
X352475Y509057D01*
G01X383858Y496063D02*
X351231Y501282D01*
G01X442287Y503937D02*
X384484D01*
G01X442913Y496063D02*
X383858D01*
G01X342529Y530315D02*
Y520720D01*
G01X334655Y562992D02*
Y520720D01*
G01X346466Y570866D02*
G03X342529Y566929I0J-3937D01*
G01X334655Y555512D02*
G03X342529I3937J0D01*
G01X346466Y570866D02*
X480325D01*
G01X334655Y562992D02*
G03X326781Y570866I-7874J0D01*
G01X342529Y566929D02*
Y555512D01*
G01X415943Y539991D02*
G03I-4291J0D01*
G01X474316Y509060D02*
X442287Y503937D01*
G01X475560Y501285D02*
X442913Y496063D01*
G01X492136Y530315D02*
G03X484262I-3937J0D01*
G01X474316Y509060D02*
G03X484262Y520723I-1865J11663D01*
G01X475560Y501285D02*
G03X492136Y520723I-3109J19438D01*
G01X484262Y530315D02*
Y520723D01*
G01X492136Y562992D02*
Y520723D01*
G01X484262Y566929D02*
G03X480325Y570866I-3937J0D01*
G01X484262Y555512D02*
G03X492136I3937J0D01*
G01X500010Y570866D02*
G03X492136Y562992I0J-7874D01*
G01X500010Y570866D02*
X818897D01*
G01X484262Y566929D02*
Y555512D01*
G01X537401Y371299D02*
G03I-5905J0D01*
G01X538386Y531496D02*
G03I-6890J0D01*
G01X628416Y0D02*
G03Y-7874I0J-3937D01*
G01X597707D02*
G03Y0I0J3937D01*
G01X780315Y-7874D02*
X628416D01*
G01X602362Y116141D02*
G03I-5906J0D01*
G01X817003Y-86834D02*
G03I-4292J0D01*
G01X811771Y-102362D02*
G03X826771Y-87362I0J15000D01*
G01X811023Y0D02*
G03Y-7874I0J-3937D01*
G01X780315D02*
G03Y0I0J3937D01*
G01X822834Y-7874D02*
X811023D01*
G01X818897Y0D02*
G03X826771Y7874I0J7874D01*
G01X818897Y0D02*
X807086D01*
G01X787401Y198819D02*
G03I-5905J0D01*
G01X792421Y499724D02*
G03I-3051J0D01*
G01X793504Y535157D02*
G03I-4134J0D01*
G01X796653Y517441D02*
G03I-7283J0D01*
G01X826771Y562992D02*
G03X818897Y570866I-7874J0D01*
G01X826771Y-11811D02*
Y-87362D01*
G01Y-11811D02*
G03X822834Y-7874I-3937J0D01*
G01X826771Y562992D02*
Y7874D01*
M02*
